FILE_TYPE = MACRO_DRAWING;
SET COLOR_WIRE YELLOW;
SET COLOR_PROP ORANGE;
SET COLOR_DOT WHITE;
SET COLOR_ARC YELLOW;
SET COLOR_BODY GREEN;
SET COLOR_NOTE PURPLE;
SET PROP_DISPLAY VALUE;
SET PAGE_NUMBER P195;
FORCEADD 9QXL2001BNHGI8..1
(-3200 2275);
FORCEPROP 1 LAST PART_NUMBER AJ020010003
J 0
(-3620 4283);
DISPLAY 0.723404 (-3620 4283);
PAINT GREEN (-3620 4283);
DISPLAY INVISIBLE (-3620 4283);
FORCEPROP 2 LAST PART_TYPE SMLF
J 0
(-3600 4525);
DISPLAY 1.021277 (-3600 4525);
FORCEPROP 1 LAST MATERIAL IC
J 0
(-3620 4156);
DISPLAY 0.723404 (-3620 4156);
PAINT GREEN (-3620 4156);
FORCEPROP 2 LAST VALUE 9QXL2001BNHGI8
J 0
(-3600 4475);
DISPLAY 1.021277 (-3600 4475);
FORCEPROP 1 LAST $LOCATION U38
J 0
(-3620 4430);
DISPLAY 0.723404 (-3620 4430);
PAINT GREEN (-3620 4430);
FORCEPROP 0 LASTPIN (-3775 3400) $PN B4
J 2
(-3785 3410);
DISPLAY 0.680851 (-3785 3410);
PAINT MONO (-3785 3410);
FORCEPROP 0 LASTPIN (-3775 3450) $PN B8
J 2
(-3785 3460);
DISPLAY 0.680851 (-3785 3460);
PAINT MONO (-3785 3460);
FORCEPROP 0 LASTPIN (-2625 4000) $PN J1
J 0
(-2615 4010);
DISPLAY 0.680851 (-2615 4010);
PAINT MONO (-2615 4010);
FORCEPROP 0 LASTPIN (-2625 3950) $PN K1
J 0
(-2615 3960);
DISPLAY 0.680851 (-2615 3960);
PAINT MONO (-2615 3960);
FORCEPROP 0 LASTPIN (-2625 3850) $PN L1
J 0
(-2615 3860);
DISPLAY 0.680851 (-2615 3860);
PAINT MONO (-2615 3860);
FORCEPROP 0 LASTPIN (-2625 3800) $PN M1
J 0
(-2615 3810);
DISPLAY 0.680851 (-2615 3810);
PAINT MONO (-2615 3810);
FORCEPROP 0 LASTPIN (-2625 3700) $PN M2
J 0
(-2615 3710);
DISPLAY 0.680851 (-2615 3710);
PAINT MONO (-2615 3710);
FORCEPROP 0 LASTPIN (-2625 3650) $PN M3
J 0
(-2615 3660);
DISPLAY 0.680851 (-2615 3660);
PAINT MONO (-2615 3660);
FORCEPROP 0 LASTPIN (-2625 3550) $PN M4
J 0
(-2615 3560);
DISPLAY 0.680851 (-2615 3560);
PAINT MONO (-2615 3560);
FORCEPROP 0 LASTPIN (-2625 3500) $PN M5
J 0
(-2615 3510);
DISPLAY 0.680851 (-2615 3510);
PAINT MONO (-2615 3510);
FORCEPROP 0 LASTPIN (-2625 3400) $PN M7
J 0
(-2615 3410);
DISPLAY 0.680851 (-2615 3410);
PAINT MONO (-2615 3410);
FORCEPROP 0 LASTPIN (-2625 3350) $PN M8
J 0
(-2615 3360);
DISPLAY 0.680851 (-2615 3360);
PAINT MONO (-2615 3360);
FORCEPROP 0 LASTPIN (-2625 3250) $PN M9
J 0
(-2615 3260);
DISPLAY 0.680851 (-2615 3260);
PAINT MONO (-2615 3260);
FORCEPROP 0 LASTPIN (-2625 3200) $PN M10
J 0
(-2615 3210);
DISPLAY 0.680851 (-2615 3210);
PAINT MONO (-2615 3210);
FORCEPROP 0 LASTPIN (-2625 3100) $PN M11
J 0
(-2615 3110);
DISPLAY 0.680851 (-2615 3110);
PAINT MONO (-2615 3110);
FORCEPROP 0 LASTPIN (-2625 3050) $PN M12
J 0
(-2615 3060);
DISPLAY 0.680851 (-2615 3060);
PAINT MONO (-2615 3060);
FORCEPROP 0 LASTPIN (-2625 2950) $PN L12
J 0
(-2615 2960);
DISPLAY 0.680851 (-2615 2960);
PAINT MONO (-2615 2960);
FORCEPROP 0 LASTPIN (-2625 2900) $PN K12
J 0
(-2615 2910);
DISPLAY 0.680851 (-2615 2910);
PAINT MONO (-2615 2910);
FORCEPROP 0 LASTPIN (-2625 2800) $PN J12
J 0
(-2615 2810);
DISPLAY 0.680851 (-2615 2810);
PAINT MONO (-2615 2810);
FORCEPROP 0 LASTPIN (-2625 2750) $PN H12
J 0
(-2615 2760);
DISPLAY 0.680851 (-2615 2760);
PAINT MONO (-2615 2760);
FORCEPROP 0 LASTPIN (-2625 2650) $PN G12
J 0
(-2615 2660);
DISPLAY 0.680851 (-2615 2660);
PAINT MONO (-2615 2660);
FORCEPROP 0 LASTPIN (-2625 2600) $PN F12
J 0
(-2615 2610);
DISPLAY 0.680851 (-2615 2610);
PAINT MONO (-2615 2610);
FORCEPROP 0 LASTPIN (-2625 2500) $PN D12
J 0
(-2615 2510);
DISPLAY 0.680851 (-2615 2510);
PAINT MONO (-2615 2510);
FORCEPROP 0 LASTPIN (-2625 2450) $PN C12
J 0
(-2615 2460);
DISPLAY 0.680851 (-2615 2460);
PAINT MONO (-2615 2460);
FORCEPROP 0 LASTPIN (-2625 2350) $PN B12
J 0
(-2615 2360);
DISPLAY 0.680851 (-2615 2360);
PAINT MONO (-2615 2360);
FORCEPROP 0 LASTPIN (-2625 2300) $PN A12
J 0
(-2615 2310);
DISPLAY 0.680851 (-2615 2310);
PAINT MONO (-2615 2310);
FORCEPROP 0 LASTPIN (-2625 2200) $PN A11
J 0
(-2615 2210);
DISPLAY 0.680851 (-2615 2210);
PAINT MONO (-2615 2210);
FORCEPROP 0 LASTPIN (-2625 2150) $PN A10
J 0
(-2615 2160);
DISPLAY 0.680851 (-2615 2160);
PAINT MONO (-2615 2160);
FORCEPROP 0 LASTPIN (-2625 2050) $PN A9
J 0
(-2615 2060);
DISPLAY 0.680851 (-2615 2060);
PAINT MONO (-2615 2060);
FORCEPROP 0 LASTPIN (-2625 2000) $PN A8
J 0
(-2615 2010);
DISPLAY 0.680851 (-2615 2010);
PAINT MONO (-2615 2010);
FORCEPROP 0 LASTPIN (-2625 1900) $PN A7
J 0
(-2615 1910);
DISPLAY 0.680851 (-2615 1910);
PAINT MONO (-2615 1910);
FORCEPROP 0 LASTPIN (-2625 1850) $PN A6
J 0
(-2615 1860);
DISPLAY 0.680851 (-2615 1860);
PAINT MONO (-2615 1860);
FORCEPROP 0 LASTPIN (-2625 1750) $PN A5
J 0
(-2615 1760);
DISPLAY 0.680851 (-2615 1760);
PAINT MONO (-2615 1760);
FORCEPROP 0 LASTPIN (-2625 1700) $PN A4
J 0
(-2615 1710);
DISPLAY 0.680851 (-2615 1710);
PAINT MONO (-2615 1710);
FORCEPROP 0 LASTPIN (-2625 1600) $PN A3
J 0
(-2615 1610);
DISPLAY 0.680851 (-2615 1610);
PAINT MONO (-2615 1610);
FORCEPROP 0 LASTPIN (-2625 1550) $PN A2
J 0
(-2615 1560);
DISPLAY 0.680851 (-2615 1560);
PAINT MONO (-2615 1560);
FORCEPROP 0 LASTPIN (-2625 1450) $PN A1
J 0
(-2615 1460);
DISPLAY 0.680851 (-2615 1460);
PAINT MONO (-2615 1460);
FORCEPROP 0 LASTPIN (-2625 1400) $PN B1
J 0
(-2615 1410);
DISPLAY 0.680851 (-2615 1410);
PAINT MONO (-2615 1410);
FORCEPROP 0 LASTPIN (-2625 1300) $PN C1
J 0
(-2615 1310);
DISPLAY 0.680851 (-2615 1310);
PAINT MONO (-2615 1310);
FORCEPROP 0 LASTPIN (-2625 1250) $PN D1
J 0
(-2615 1260);
DISPLAY 0.680851 (-2615 1260);
PAINT MONO (-2615 1260);
FORCEPROP 0 LASTPIN (-2625 1150) $PN E1
J 0
(-2615 1160);
DISPLAY 0.680851 (-2615 1160);
PAINT MONO (-2615 1160);
FORCEPROP 0 LASTPIN (-2625 1100) $PN F1
J 0
(-2615 1110);
DISPLAY 0.680851 (-2615 1110);
PAINT MONO (-2615 1110);
FORCEPROP 0 LASTPIN (-3775 3650) $PN G1
J 2
(-3785 3660);
DISPLAY 0.680851 (-3785 3660);
PAINT MONO (-3785 3660);
FORCEPROP 0 LASTPIN (-3775 3600) $PN H1
J 2
(-3785 3610);
DISPLAY 0.680851 (-3785 3610);
PAINT MONO (-3785 3610);
FORCEPROP 0 LASTPIN (-2625 500) $PN TH
J 0
(-2615 510);
DISPLAY 0.680851 (-2615 510);
PAINT MONO (-2615 510);
FORCEPROP 0 LASTPIN (-3775 1600) $PN B3
J 2
(-3785 1610);
DISPLAY 0.680851 (-3785 1610);
PAINT MONO (-3785 1610);
FORCEPROP 0 LASTPIN (-3775 1550) $PN B5
J 2
(-3785 1560);
DISPLAY 0.680851 (-3785 1560);
PAINT MONO (-3785 1560);
FORCEPROP 0 LASTPIN (-3775 1500) $PN B7
J 2
(-3785 1510);
DISPLAY 0.680851 (-3785 1510);
PAINT MONO (-3785 1510);
FORCEPROP 0 LASTPIN (-3775 1450) $PN B9
J 2
(-3785 1460);
DISPLAY 0.680851 (-3785 1460);
PAINT MONO (-3785 1460);
FORCEPROP 0 LASTPIN (-3775 1400) $PN C2
J 2
(-3785 1410);
DISPLAY 0.680851 (-3785 1410);
PAINT MONO (-3785 1410);
FORCEPROP 0 LASTPIN (-3775 1350) $PN D2
J 2
(-3785 1360);
DISPLAY 0.680851 (-3785 1360);
PAINT MONO (-3785 1360);
FORCEPROP 0 LASTPIN (-3775 1300) $PN D11
J 2
(-3785 1310);
DISPLAY 0.680851 (-3785 1310);
PAINT MONO (-3785 1310);
FORCEPROP 0 LASTPIN (-3775 1250) $PN F2
J 2
(-3785 1260);
DISPLAY 0.680851 (-3785 1260);
PAINT MONO (-3785 1260);
FORCEPROP 0 LASTPIN (-3775 1200) $PN F11
J 2
(-3785 1210);
DISPLAY 0.680851 (-3785 1210);
PAINT MONO (-3785 1210);
FORCEPROP 0 LASTPIN (-3775 1150) $PN G2
J 2
(-3785 1160);
DISPLAY 0.680851 (-3785 1160);
PAINT MONO (-3785 1160);
FORCEPROP 0 LASTPIN (-3775 1100) $PN G11
J 2
(-3785 1110);
DISPLAY 0.680851 (-3785 1110);
PAINT MONO (-3785 1110);
FORCEPROP 0 LASTPIN (-3775 1050) $PN J2
J 2
(-3785 1060);
DISPLAY 0.680851 (-3785 1060);
PAINT MONO (-3785 1060);
FORCEPROP 0 LASTPIN (-3775 1000) $PN J11
J 2
(-3785 1010);
DISPLAY 0.680851 (-3785 1010);
PAINT MONO (-3785 1010);
FORCEPROP 0 LASTPIN (-3775 950) $PN K2
J 2
(-3785 960);
DISPLAY 0.680851 (-3785 960);
PAINT MONO (-3785 960);
FORCEPROP 0 LASTPIN (-3775 900) $PN L6
J 2
(-3785 910);
DISPLAY 0.680851 (-3785 910);
PAINT MONO (-3785 910);
FORCEPROP 0 LASTPIN (-3775 850) $PN L7
J 2
(-3785 860);
DISPLAY 0.680851 (-3785 860);
PAINT MONO (-3785 860);
FORCEPROP 0 LASTPIN (-3775 800) $PN L3
J 2
(-3785 810);
DISPLAY 0.680851 (-3785 810);
PAINT MONO (-3785 810);
FORCEPROP 0 LASTPIN (-3775 750) $PN L9
J 2
(-3785 760);
DISPLAY 0.680851 (-3785 760);
PAINT MONO (-3785 760);
FORCEPROP 0 LASTPIN (-3775 3250) $PN L5
J 2
(-3785 3260);
DISPLAY 0.680851 (-3785 3260);
PAINT MONO (-3785 3260);
FORCEPROP 0 LASTPIN (-3775 3300) $PN L4
J 2
(-3785 3310);
DISPLAY 0.680851 (-3785 3310);
PAINT MONO (-3785 3310);
FORCEPROP 0 LASTPIN (-3775 2550) $PN M6
J 2
(-3785 2560);
DISPLAY 0.680851 (-3785 2560);
PAINT MONO (-3785 2560);
FORCEPROP 0 LASTPIN (-3775 3850) $PN B6
J 2
(-3785 3860);
DISPLAY 0.680851 (-3785 3860);
PAINT MONO (-3785 3860);
FORCEPROP 0 LASTPIN (-3775 4100) $PN B2
J 2
(-3785 4110);
DISPLAY 0.680851 (-3785 4110);
PAINT MONO (-3785 4110);
FORCEPROP 0 LASTPIN (-3775 4050) $PN B11
J 2
(-3785 4060);
DISPLAY 0.680851 (-3785 4060);
PAINT MONO (-3785 4060);
FORCEPROP 0 LASTPIN (-3775 4000) $PN L2
J 2
(-3785 4010);
DISPLAY 0.680851 (-3785 4010);
PAINT MONO (-3785 4010);
FORCEPROP 0 LASTPIN (-3775 3950) $PN L11
J 2
(-3785 3960);
DISPLAY 0.680851 (-3785 3960);
PAINT MONO (-3785 3960);
FORCEPROP 0 LASTPIN (-3775 3800) $PN H2
J 2
(-3785 3810);
DISPLAY 0.680851 (-3785 3810);
PAINT MONO (-3785 3810);
FORCEPROP 0 LASTPIN (-3775 2250) $PN L8
J 2
(-3785 2260);
DISPLAY 0.680851 (-3785 2260);
PAINT MONO (-3785 2260);
FORCEPROP 0 LASTPIN (-3775 2200) $PN L10
J 2
(-3785 2210);
DISPLAY 0.680851 (-3785 2210);
PAINT MONO (-3785 2210);
FORCEPROP 0 LASTPIN (-3775 2150) $PN K11
J 2
(-3785 2160);
DISPLAY 0.680851 (-3785 2160);
PAINT MONO (-3785 2160);
FORCEPROP 0 LASTPIN (-3775 2100) $PN H11
J 2
(-3785 2110);
DISPLAY 0.680851 (-3785 2110);
PAINT MONO (-3785 2110);
FORCEPROP 0 LASTPIN (-3775 2050) $PN E12
J 2
(-3785 2060);
DISPLAY 0.680851 (-3785 2060);
PAINT MONO (-3785 2060);
FORCEPROP 0 LASTPIN (-3775 2000) $PN E11
J 2
(-3785 2010);
DISPLAY 0.680851 (-3785 2010);
PAINT MONO (-3785 2010);
FORCEPROP 0 LASTPIN (-3775 1950) $PN C11
J 2
(-3785 1960);
DISPLAY 0.680851 (-3785 1960);
PAINT MONO (-3785 1960);
FORCEPROP 0 LASTPIN (-3775 1900) $PN B10
J 2
(-3785 1910);
DISPLAY 0.680851 (-3785 1910);
PAINT MONO (-3785 1910);
FORCEPROP 0 LASTPIN (-3775 3050) $PN E2
J 2
(-3785 3060);
DISPLAY 0.680851 (-3785 3060);
PAINT MONO (-3785 3060);
FORCEPROP 1 LAST CDS_LMAN_SYM_OUTLINE -425,1875,425,-1875
J 0
(-3200 2275);
DISPLAY 0.468085 (-3200 2275);
PAINT GREEN (-3200 2275);
DISPLAY INVISIBLE (-3200 2275);
FORCEPROP 1 LAST NEEDS_NO_SIZE TRUE
J 0
(-3200 2275);
DISPLAY 0.723404 (-3200 2275);
PAINT GREEN (-3200 2275);
DISPLAY INVISIBLE (-3200 2275);
FORCEPROP 1 LAST PATH I119
J 0
(-3200 2275);
DISPLAY 0.723404 (-3200 2275);
PAINT GREEN (-3200 2275);
DISPLAY INVISIBLE (-3200 2275);
FORCEPROP 2 LAST CDS_LIB pure_quanta
J 0
(-3200 2275);
DISPLAY INVISIBLE (-3200 2275);
FORCEPROP 2 LAST CDS_LOCATION U38
J 0
(-3600 4575);
DISPLAY 1.021277 (-3600 4575);
DISPLAY INVISIBLE (-3600 4575);
FORCEPROP 0 LAST $SEC 1
J 0
(-3600 4575);
DISPLAY 0.680851 (-3600 4575);
PAINT MONO (-3600 4575);
DISPLAY INVISIBLE (-3600 4575);
FORCEPROP 0 LAST CDS_SEC 1
J 0
(-3600 4575);
DISPLAY 1.021277 (-3600 4575);
DISPLAY INVISIBLE (-3600 4575);
FORCEADD OFFPAGE..2
(-1250 3950);
FORCEPROP 2 LAST $XR0 13 
J 0
(-1061 3950);
DISPLAY 0.638298 (-1061 3950);
PAINT MONO (-1061 3950);
FORCEPROP 2 LAST CDS_LIB standard
J 0
(-1250 3950);
PAINT MONO (-1250 3950);
DISPLAY INVISIBLE (-1250 3950);
FORCEPROP 1 LAST OFFPAGE TRUE
J 0
(-925 3825);
DISPLAY 0.872340 (-925 3825);
PAINT GREEN (-925 3825);
DISPLAY INVISIBLE (-925 3825);
FORCEPROP 1 LAST COMMENT_BODY TRUE
J 0
(-1295 3855);
DISPLAY 0.872340 (-1295 3855);
PAINT GREEN (-1295 3855);
DISPLAY INVISIBLE (-1295 3855);
FORCEPROP 2 LAST PATH I120
J 0
(-1075 4025);
DISPLAY 1.021277 (-1075 4025);
DISPLAY INVISIBLE (-1075 4025);
FORCEADD OFFPAGE..2
(-1250 4000);
FORCEPROP 2 LAST $XR0 13 
J 0
(-1061 4000);
DISPLAY 0.638298 (-1061 4000);
PAINT MONO (-1061 4000);
FORCEPROP 1 LAST OFFPAGE TRUE
J 0
(-925 3875);
DISPLAY 0.872340 (-925 3875);
PAINT GREEN (-925 3875);
DISPLAY INVISIBLE (-925 3875);
FORCEPROP 1 LAST COMMENT_BODY TRUE
J 0
(-1295 3905);
DISPLAY 0.872340 (-1295 3905);
PAINT GREEN (-1295 3905);
DISPLAY INVISIBLE (-1295 3905);
FORCEPROP 2 LAST CDS_LIB standard
J 0
(-1250 4000);
PAINT MONO (-1250 4000);
DISPLAY INVISIBLE (-1250 4000);
FORCEPROP 2 LAST PATH I121
J 0
(-1075 4075);
DISPLAY 1.021277 (-1075 4075);
DISPLAY INVISIBLE (-1075 4075);
FORCEADD OFFPAGE..2
(-1250 3800);
FORCEPROP 2 LAST $XR0 13 
J 0
(-1061 3800);
DISPLAY 0.638298 (-1061 3800);
PAINT MONO (-1061 3800);
FORCEPROP 2 LAST CDS_LIB standard
J 0
(-1250 3800);
PAINT MONO (-1250 3800);
DISPLAY INVISIBLE (-1250 3800);
FORCEPROP 1 LAST OFFPAGE TRUE
J 0
(-925 3675);
DISPLAY 0.872340 (-925 3675);
PAINT GREEN (-925 3675);
DISPLAY INVISIBLE (-925 3675);
FORCEPROP 1 LAST COMMENT_BODY TRUE
J 0
(-1295 3705);
DISPLAY 0.872340 (-1295 3705);
PAINT GREEN (-1295 3705);
DISPLAY INVISIBLE (-1295 3705);
FORCEPROP 2 LAST PATH I122
J 0
(-1075 3875);
DISPLAY 1.021277 (-1075 3875);
DISPLAY INVISIBLE (-1075 3875);
FORCEADD OFFPAGE..2
(-1250 3850);
FORCEPROP 2 LAST $XR0 13 
J 0
(-1061 3850);
DISPLAY 0.638298 (-1061 3850);
PAINT MONO (-1061 3850);
FORCEPROP 1 LAST OFFPAGE TRUE
J 0
(-925 3725);
DISPLAY 0.872340 (-925 3725);
PAINT GREEN (-925 3725);
DISPLAY INVISIBLE (-925 3725);
FORCEPROP 1 LAST COMMENT_BODY TRUE
J 0
(-1295 3755);
DISPLAY 0.872340 (-1295 3755);
PAINT GREEN (-1295 3755);
DISPLAY INVISIBLE (-1295 3755);
FORCEPROP 2 LAST CDS_LIB standard
J 0
(-1250 3850);
PAINT MONO (-1250 3850);
DISPLAY INVISIBLE (-1250 3850);
FORCEPROP 2 LAST PATH I123
J 0
(-1075 3925);
DISPLAY 1.021277 (-1075 3925);
DISPLAY INVISIBLE (-1075 3925);
FORCEADD OFFPAGE..2
(-1250 3550);
FORCEPROP 2 LAST $XR0 13 
J 0
(-1061 3550);
DISPLAY 0.638298 (-1061 3550);
PAINT MONO (-1061 3550);
FORCEPROP 1 LAST OFFPAGE TRUE
J 0
(-925 3425);
DISPLAY 0.872340 (-925 3425);
PAINT GREEN (-925 3425);
DISPLAY INVISIBLE (-925 3425);
FORCEPROP 1 LAST COMMENT_BODY TRUE
J 0
(-1295 3455);
DISPLAY 0.872340 (-1295 3455);
PAINT GREEN (-1295 3455);
DISPLAY INVISIBLE (-1295 3455);
FORCEPROP 2 LAST CDS_LIB standard
J 0
(-1250 3550);
PAINT MONO (-1250 3550);
DISPLAY INVISIBLE (-1250 3550);
FORCEPROP 2 LAST PATH I126
J 0
(-1075 3625);
DISPLAY 1.021277 (-1075 3625);
DISPLAY INVISIBLE (-1075 3625);
FORCEADD OFFPAGE..2
(-1250 3500);
FORCEPROP 2 LAST $XR0 13 
J 0
(-1061 3500);
DISPLAY 0.638298 (-1061 3500);
PAINT MONO (-1061 3500);
FORCEPROP 2 LAST CDS_LIB standard
J 0
(-1250 3500);
PAINT MONO (-1250 3500);
DISPLAY INVISIBLE (-1250 3500);
FORCEPROP 1 LAST OFFPAGE TRUE
J 0
(-925 3375);
DISPLAY 0.872340 (-925 3375);
PAINT GREEN (-925 3375);
DISPLAY INVISIBLE (-925 3375);
FORCEPROP 1 LAST COMMENT_BODY TRUE
J 0
(-1295 3405);
DISPLAY 0.872340 (-1295 3405);
PAINT GREEN (-1295 3405);
DISPLAY INVISIBLE (-1295 3405);
FORCEPROP 2 LAST PATH I127
J 0
(-1075 3575);
DISPLAY 1.021277 (-1075 3575);
DISPLAY INVISIBLE (-1075 3575);
FORCEADD OFFPAGE..2
(-1250 3700);
FORCEPROP 2 LAST $XR0 13 
J 0
(-1061 3700);
DISPLAY 0.638298 (-1061 3700);
PAINT MONO (-1061 3700);
FORCEPROP 1 LAST OFFPAGE TRUE
J 0
(-925 3575);
DISPLAY 0.872340 (-925 3575);
PAINT GREEN (-925 3575);
DISPLAY INVISIBLE (-925 3575);
FORCEPROP 1 LAST COMMENT_BODY TRUE
J 0
(-1295 3605);
DISPLAY 0.872340 (-1295 3605);
PAINT GREEN (-1295 3605);
DISPLAY INVISIBLE (-1295 3605);
FORCEPROP 2 LAST CDS_LIB standard
J 0
(-1250 3700);
PAINT MONO (-1250 3700);
DISPLAY INVISIBLE (-1250 3700);
FORCEPROP 2 LAST PATH I128
J 0
(-1075 3775);
DISPLAY 1.021277 (-1075 3775);
DISPLAY INVISIBLE (-1075 3775);
FORCEADD OFFPAGE..2
(-1250 3650);
FORCEPROP 2 LAST $XR0 13 
J 0
(-1061 3650);
DISPLAY 0.638298 (-1061 3650);
PAINT MONO (-1061 3650);
FORCEPROP 2 LAST CDS_LIB standard
J 0
(-1250 3650);
PAINT MONO (-1250 3650);
DISPLAY INVISIBLE (-1250 3650);
FORCEPROP 1 LAST OFFPAGE TRUE
J 0
(-925 3525);
DISPLAY 0.872340 (-925 3525);
PAINT GREEN (-925 3525);
DISPLAY INVISIBLE (-925 3525);
FORCEPROP 1 LAST COMMENT_BODY TRUE
J 0
(-1295 3555);
DISPLAY 0.872340 (-1295 3555);
PAINT GREEN (-1295 3555);
DISPLAY INVISIBLE (-1295 3555);
FORCEPROP 2 LAST PATH I129
J 0
(-1075 3725);
DISPLAY 1.021277 (-1075 3725);
DISPLAY INVISIBLE (-1075 3725);
FORCEADD OFFPAGE..1
(-4875 3650);
FORCEPROP 2 LAST $XR0 208 
J 0
(-5157 3650);
DISPLAY 0.638298 (-5157 3650);
PAINT MONO (-5157 3650);
FORCEPROP 2 LAST PATH I150
J 0
(-4825 3725);
DISPLAY 1.021277 (-4825 3725);
DISPLAY INVISIBLE (-4825 3725);
FORCEPROP 1 LAST OFFPAGE TRUE
J 0
(-4550 3525);
DISPLAY 0.872340 (-4550 3525);
PAINT GREEN (-4550 3525);
DISPLAY INVISIBLE (-4550 3525);
FORCEPROP 1 LAST COMMENT_BODY TRUE
J 0
(-4750 3550);
DISPLAY 0.872340 (-4750 3550);
PAINT GREEN (-4750 3550);
DISPLAY INVISIBLE (-4750 3550);
FORCEPROP 2 LAST CDS_LIB standard
J 0
(-4875 3650);
PAINT MONO (-4875 3650);
DISPLAY INVISIBLE (-4875 3650);
FORCEADD OFFPAGE..1
(-4875 3600);
FORCEPROP 2 LAST $XR0 208 
J 0
(-5157 3600);
DISPLAY 0.638298 (-5157 3600);
PAINT MONO (-5157 3600);
FORCEPROP 2 LAST PATH I151
J 0
(-4825 3675);
DISPLAY 1.021277 (-4825 3675);
DISPLAY INVISIBLE (-4825 3675);
FORCEPROP 1 LAST COMMENT_BODY TRUE
J 0
(-4750 3500);
DISPLAY 0.872340 (-4750 3500);
PAINT GREEN (-4750 3500);
DISPLAY INVISIBLE (-4750 3500);
FORCEPROP 1 LAST OFFPAGE TRUE
J 0
(-4550 3475);
DISPLAY 0.872340 (-4550 3475);
PAINT GREEN (-4550 3475);
DISPLAY INVISIBLE (-4550 3475);
FORCEPROP 2 LAST CDS_LIB standard
J 0
(-4875 3600);
PAINT MONO (-4875 3600);
DISPLAY INVISIBLE (-4875 3600);
FORCEADD OFFPAGE..1
(-4875 3050);
FORCEPROP 2 LAST $XR0 206 
J 0
(-5157 3050);
DISPLAY 0.638298 (-5157 3050);
PAINT MONO (-5157 3050);
FORCEPROP 2 LAST PATH I154
J 0
(-4825 3125);
DISPLAY 1.021277 (-4825 3125);
DISPLAY INVISIBLE (-4825 3125);
FORCEPROP 1 LAST COMMENT_BODY TRUE
J 0
(-4750 2950);
DISPLAY 0.872340 (-4750 2950);
PAINT GREEN (-4750 2950);
DISPLAY INVISIBLE (-4750 2950);
FORCEPROP 1 LAST OFFPAGE TRUE
J 0
(-4550 2925);
DISPLAY 0.872340 (-4550 2925);
PAINT GREEN (-4550 2925);
DISPLAY INVISIBLE (-4550 2925);
FORCEPROP 2 LAST CDS_LIB standard
J 0
(-4875 3050);
PAINT MONO (-4875 3050);
DISPLAY INVISIBLE (-4875 3050);
FORCEADD Q_RES..1
(-5300 2250);
FORCEPROP 1 LAST PART_NUMBER CS04992FB07
J 0
(-5425 2325);
DISPLAY 0.510638 (-5425 2325);
DISPLAY INVISIBLE (-5425 2325);
FORCEPROP 1 LAST WATTAGE 1/16W
J 2
(-5125 2375);
DISPLAY 0.510638 (-5125 2375);
FORCEPROP 1 LAST VALUE 49.9
J 2
(-5075 2250);
DISPLAY 0.510638 (-5075 2250);
FORCEPROP 1 LAST PACK_TYPE 0402LF
J 0
(-5425 2375);
DISPLAY 0.510638 (-5425 2375);
FORCEPROP 1 LAST TOLERANCE 1%
J 0
(-5050 2250);
DISPLAY 0.510638 (-5050 2250);
FORCEPROP 1 LAST MATERIAL CHIP
J 0
(-4975 2250);
DISPLAY 0.510638 (-4975 2250);
FORCEPROP 1 LAST $LOCATION R576
J 0
(-5525 2250);
DISPLAY 0.510638 (-5525 2250);
FORCEPROP 1 LASTPIN (-5400 2250) $PN 1
J 0
(-5388 2262);
DISPLAY 0.787234 (-5388 2262);
FORCEPROP 1 LASTPIN (-5200 2250) $PN 2
J 0
(-5238 2262);
DISPLAY 0.787234 (-5238 2262);
FORCEPROP 1 LAST PATH I156
J 0
(-5350 2400);
DISPLAY 0.978723 (-5350 2400);
PAINT WHITE (-5350 2400);
DISPLAY INVISIBLE (-5350 2400);
FORCEPROP 2 LAST CDS_LIB pure_quanta
J 0
(-5300 2250);
PAINT MONO (-5300 2250);
DISPLAY INVISIBLE (-5300 2250);
FORCEPROP 2 LAST CDS_LOCATION R576
J 0
(-5350 2450);
DISPLAY 1.021277 (-5350 2450);
DISPLAY INVISIBLE (-5350 2450);
FORCEPROP 2 LAST $SEC 1
J 0
(-5350 2450);
DISPLAY 0.680851 (-5350 2450);
PAINT MONO (-5350 2450);
DISPLAY INVISIBLE (-5350 2450);
FORCEPROP 2 LAST CDS_SEC 1
J 0
(-5350 2450);
DISPLAY 1.021277 (-5350 2450);
DISPLAY INVISIBLE (-5350 2450);
FORCEADD OFFPAGE..1
(-6200 2250);
FORCEPROP 2 LAST $XR0 223 
J 0
(-6482 2250);
DISPLAY 0.638298 (-6482 2250);
PAINT MONO (-6482 2250);
FORCEPROP 2 LAST PATH I157
J 0
(-6150 2325);
DISPLAY 1.021277 (-6150 2325);
DISPLAY INVISIBLE (-6150 2325);
FORCEPROP 2 LAST CDS_LIB standard
J 0
(-6200 2250);
PAINT MONO (-6200 2250);
DISPLAY INVISIBLE (-6200 2250);
FORCEPROP 1 LAST OFFPAGE TRUE
J 0
(-5875 2125);
DISPLAY 0.872340 (-5875 2125);
PAINT GREEN (-5875 2125);
DISPLAY INVISIBLE (-5875 2125);
FORCEPROP 1 LAST COMMENT_BODY TRUE
J 0
(-6075 2150);
DISPLAY 0.872340 (-6075 2150);
PAINT GREEN (-6075 2150);
DISPLAY INVISIBLE (-6075 2150);
FORCEADD UNIVERSAL_POWER..1
(-4125 4250);
FORCEPROP 3 LASTPIN (-4125 4200) SIG_NAME P3V3_DB2000_VDD\g
J 0
(-4115 4210);
DISPLAY 0.659574 (-4115 4210);
PAINT MONO (-4115 4210);
DISPLAY INVISIBLE (-4115 4210);
FORCEPROP 1 LAST HDL_POWER P3V3_DB2000_VDD
J 1
(-4125 4300);
DISPLAY 0.872340 (-4125 4300);
PAINT GREEN (-4125 4300);
FORCEPROP 2 LAST CDS_LIB logical_power
J 0
(-4125 4250);
PAINT MONO (-4125 4250);
DISPLAY INVISIBLE (-4125 4250);
FORCEPROP 1 LAST PATH I158
J 0
(-4075 4275);
DISPLAY 0.872340 (-4075 4275);
PAINT AQUA (-4075 4275);
DISPLAY INVISIBLE (-4075 4275);
FORCEADD UNIVERSAL_POWER..1
(-4575 4350);
FORCEPROP 3 LASTPIN (-4575 4300) SIG_NAME P3V3_DB2000_VDDA\g
J 0
(-4565 4310);
DISPLAY 0.659574 (-4565 4310);
PAINT MONO (-4565 4310);
DISPLAY INVISIBLE (-4565 4310);
FORCEPROP 1 LAST HDL_POWER P3V3_DB2000_VDDA
J 1
(-4575 4400);
DISPLAY 0.872340 (-4575 4400);
PAINT GREEN (-4575 4400);
FORCEPROP 2 LAST CDS_LIB logical_power
J 0
(-4575 4350);
PAINT MONO (-4575 4350);
DISPLAY INVISIBLE (-4575 4350);
FORCEPROP 1 LAST PATH I159
J 0
(-4525 4375);
DISPLAY 0.872340 (-4525 4375);
PAINT AQUA (-4525 4375);
DISPLAY INVISIBLE (-4525 4375);
FORCEADD UNIVERSAL_POWER..1
(-5025 4450);
FORCEPROP 3 LASTPIN (-5025 4400) SIG_NAME P3V3_DB2000_VDDR\g
J 0
(-5015 4410);
DISPLAY 0.659574 (-5015 4410);
PAINT MONO (-5015 4410);
DISPLAY INVISIBLE (-5015 4410);
FORCEPROP 1 LAST HDL_POWER P3V3_DB2000_VDDR
J 1
(-5025 4500);
DISPLAY 0.872340 (-5025 4500);
PAINT GREEN (-5025 4500);
FORCEPROP 1 LAST PATH I160
J 0
(-4975 4475);
DISPLAY 0.872340 (-4975 4475);
PAINT AQUA (-4975 4475);
DISPLAY INVISIBLE (-4975 4475);
FORCEPROP 2 LAST CDS_LIB logical_power
J 0
(-5025 4450);
PAINT MONO (-5025 4450);
DISPLAY INVISIBLE (-5025 4450);
FORCEADD UNIVERSAL_POWER..1
(-9425 4500);
FORCEPROP 3 LASTPIN (-9425 4450) SIG_NAME P3V3\g
J 0
(-9415 4460);
DISPLAY 0.659574 (-9415 4460);
PAINT MONO (-9415 4460);
DISPLAY INVISIBLE (-9415 4460);
FORCEPROP 1 LAST HDL_POWER P3V3
J 1
(-9425 4550);
DISPLAY 0.872340 (-9425 4550);
PAINT GREEN (-9425 4550);
FORCEPROP 2 LAST CDS_LIB logical_power
J 0
(-9425 4500);
PAINT MONO (-9425 4500);
DISPLAY INVISIBLE (-9425 4500);
FORCEPROP 1 LAST PATH I161
J 0
(-9375 4525);
DISPLAY 0.872340 (-9375 4525);
PAINT AQUA (-9375 4525);
DISPLAY INVISIBLE (-9375 4525);
FORCEADD Q_RES..1
(-7875 3325);
FORCEPROP 1 LAST PART_NUMBER CS-2203F902
J 0
(-8100 3225);
DISPLAY 0.787234 (-8100 3225);
DISPLAY INVISIBLE (-8100 3225);
FORCEPROP 1 LAST VALUE 2.2
J 2
(-7625 3325);
DISPLAY 0.787234 (-7625 3325);
FORCEPROP 1 LAST WATTAGE 1/10W
J 2
(-7475 3150);
DISPLAY 0.787234 (-7475 3150);
FORCEPROP 1 LAST TOLERANCE 1%
J 0
(-7600 3325);
DISPLAY 0.787234 (-7600 3325);
FORCEPROP 1 LAST PACK_TYPE 0603LF
J 0
(-7925 3150);
DISPLAY 0.787234 (-7925 3150);
FORCEPROP 1 LAST MATERIAL CHIP
J 0
(-8100 3150);
DISPLAY 0.787234 (-8100 3150);
FORCEPROP 1 LAST $LOCATION R572
J 0
(-8100 3325);
DISPLAY 0.787234 (-8100 3325);
FORCEPROP 1 LASTPIN (-7975 3325) $PN 1
J 0
(-7963 3337);
DISPLAY 0.787234 (-7963 3337);
FORCEPROP 1 LASTPIN (-7775 3325) $PN 2
J 0
(-7813 3337);
DISPLAY 0.787234 (-7813 3337);
FORCEPROP 2 LAST CDS_LIB pure_quanta
J 0
(-7875 3325);
PAINT MONO (-7875 3325);
DISPLAY INVISIBLE (-7875 3325);
FORCEPROP 1 LAST PATH I162
J 0
(-7925 3475);
DISPLAY 0.978723 (-7925 3475);
PAINT WHITE (-7925 3475);
DISPLAY INVISIBLE (-7925 3475);
FORCEPROP 2 LAST CDS_LOCATION R572
J 0
(-7925 3525);
DISPLAY 1.021277 (-7925 3525);
DISPLAY INVISIBLE (-7925 3525);
FORCEPROP 2 LAST $SEC 1
J 0
(-7925 3525);
DISPLAY 0.680851 (-7925 3525);
PAINT MONO (-7925 3525);
DISPLAY INVISIBLE (-7925 3525);
FORCEPROP 2 LAST CDS_SEC 1
J 0
(-7925 3525);
DISPLAY 1.021277 (-7925 3525);
DISPLAY INVISIBLE (-7925 3525);
FORCEADD Q_RES..1
(-7875 4200);
FORCEPROP 1 LAST PART_NUMBER CS-2203F902
J 0
(-8100 4100);
DISPLAY 0.787234 (-8100 4100);
DISPLAY INVISIBLE (-8100 4100);
FORCEPROP 1 LAST TOLERANCE 1%
J 0
(-7600 4200);
DISPLAY 0.787234 (-7600 4200);
FORCEPROP 1 LAST MATERIAL CHIP
J 0
(-8100 4025);
DISPLAY 0.787234 (-8100 4025);
FORCEPROP 1 LAST VALUE 2.2
J 2
(-7625 4200);
DISPLAY 0.787234 (-7625 4200);
FORCEPROP 1 LAST PACK_TYPE 0603LF
J 0
(-7925 4025);
DISPLAY 0.787234 (-7925 4025);
FORCEPROP 1 LAST WATTAGE 1/10W
J 2
(-7475 4025);
DISPLAY 0.787234 (-7475 4025);
FORCEPROP 1 LAST $LOCATION R571
J 0
(-8100 4200);
DISPLAY 0.787234 (-8100 4200);
FORCEPROP 1 LASTPIN (-7975 4200) $PN 1
J 0
(-7963 4212);
DISPLAY 0.787234 (-7963 4212);
FORCEPROP 1 LASTPIN (-7775 4200) $PN 2
J 0
(-7813 4212);
DISPLAY 0.787234 (-7813 4212);
FORCEPROP 2 LAST CDS_LIB pure_quanta
J 0
(-7875 4200);
PAINT MONO (-7875 4200);
DISPLAY INVISIBLE (-7875 4200);
FORCEPROP 1 LAST PATH I163
J 0
(-7925 4350);
DISPLAY 0.978723 (-7925 4350);
PAINT WHITE (-7925 4350);
DISPLAY INVISIBLE (-7925 4350);
FORCEPROP 2 LAST CDS_LOCATION R571
J 0
(-7925 4400);
DISPLAY 1.021277 (-7925 4400);
DISPLAY INVISIBLE (-7925 4400);
FORCEPROP 2 LAST $SEC 1
J 0
(-7925 4400);
DISPLAY 0.680851 (-7925 4400);
PAINT MONO (-7925 4400);
DISPLAY INVISIBLE (-7925 4400);
FORCEPROP 2 LAST CDS_SEC 1
J 0
(-7925 4400);
DISPLAY 1.021277 (-7925 4400);
DISPLAY INVISIBLE (-7925 4400);
FORCEADD Q_CAP..1
(-7450 3100);
FORCEPROP 1 LAST PART_NUMBER CH6101ME900
J 0
(-7400 2950);
DISPLAY 0.510638 (-7400 2950);
DISPLAY INVISIBLE (-7400 2950);
FORCEPROP 1 LAST VALUE 10UF
J 0
(-7400 3150);
DISPLAY 0.510638 (-7400 3150);
FORCEPROP 1 LAST VOLTAGE 6.3V
J 0
(-7400 3100);
DISPLAY 0.510638 (-7400 3100);
FORCEPROP 1 LAST TOLERANCE 20%
J 0
(-7400 3050);
DISPLAY 0.510638 (-7400 3050);
FORCEPROP 1 LAST MATERIAL X6S
J 0
(-7400 3000);
DISPLAY 0.510638 (-7400 3000);
FORCEPROP 1 LAST PACK_TYPE C0603
J 0
(-7400 2900);
DISPLAY 0.510638 (-7400 2900);
FORCEPROP 1 LAST $LOCATION C209
J 0
(-7400 3200);
DISPLAY 0.978723 (-7400 3200);
FORCEPROP 1 LASTPIN (-7450 3200) $PN 1
J 0
(-7440 3180);
DISPLAY 0.787234 (-7440 3180);
FORCEPROP 1 LASTPIN (-7450 3000) $PN 2
J 0
(-7440 2980);
DISPLAY 0.787234 (-7440 2980);
FORCEPROP 2 LAST CDS_LIB pure_quanta
J 0
(-7450 3100);
PAINT MONO (-7450 3100);
DISPLAY INVISIBLE (-7450 3100);
FORCEPROP 1 LAST PATH I164
J 0
(-7400 3250);
DISPLAY 0.978723 (-7400 3250);
PAINT WHITE (-7400 3250);
DISPLAY INVISIBLE (-7400 3250);
FORCEPROP 2 LAST CDS_LOCATION C209
J 0
(-7400 3300);
DISPLAY 1.021277 (-7400 3300);
DISPLAY INVISIBLE (-7400 3300);
FORCEPROP 2 LAST $SEC 1
J 0
(-7400 3300);
DISPLAY 0.680851 (-7400 3300);
PAINT MONO (-7400 3300);
DISPLAY INVISIBLE (-7400 3300);
FORCEPROP 2 LAST CDS_SEC 1
J 0
(-7400 3300);
DISPLAY 1.021277 (-7400 3300);
DISPLAY INVISIBLE (-7400 3300);
FORCEADD Q_CAP..1
(-7075 3100);
FORCEPROP 1 LAST PART_NUMBER CH4104K1B00
J 0
(-7025 2950);
DISPLAY 0.617021 (-7025 2950);
DISPLAY INVISIBLE (-7025 2950);
FORCEPROP 1 LAST PACK_TYPE 0402
J 0
(-7025 2900);
DISPLAY 0.617021 (-7025 2900);
FORCEPROP 1 LAST MATERIAL X7R
J 0
(-7025 3000);
DISPLAY 0.617021 (-7025 3000);
FORCEPROP 1 LAST TOLERANCE 10%
J 0
(-7025 3050);
DISPLAY 0.617021 (-7025 3050);
FORCEPROP 1 LAST VOLTAGE 25V
J 0
(-7025 3100);
DISPLAY 0.617021 (-7025 3100);
FORCEPROP 1 LAST VALUE 0.1UF
J 0
(-7025 3150);
DISPLAY 0.617021 (-7025 3150);
FORCEPROP 1 LAST $LOCATION C211
J 0
(-7025 3200);
DISPLAY 0.978723 (-7025 3200);
FORCEPROP 1 LASTPIN (-7075 3200) $PN 1
J 0
(-7065 3180);
DISPLAY 0.787234 (-7065 3180);
FORCEPROP 1 LASTPIN (-7075 3000) $PN 2
J 0
(-7065 2980);
DISPLAY 0.787234 (-7065 2980);
FORCEPROP 2 LAST CDS_LIB pure_quanta
J 0
(-7075 3100);
PAINT MONO (-7075 3100);
DISPLAY INVISIBLE (-7075 3100);
FORCEPROP 1 LAST PATH I165
J 0
(-7025 3250);
DISPLAY 0.978723 (-7025 3250);
PAINT WHITE (-7025 3250);
DISPLAY INVISIBLE (-7025 3250);
FORCEPROP 2 LAST BOM_COST VR_SYSTEM 
J 0
(-7025 3250);
DISPLAY 0.680851 (-7025 3250);
DISPLAY INVISIBLE (-7025 3250);
FORCEPROP 2 LAST CDS_LOCATION C211
J 0
(-7025 3300);
DISPLAY 1.021277 (-7025 3300);
DISPLAY INVISIBLE (-7025 3300);
FORCEPROP 2 LAST $SEC 1
J 0
(-7025 3300);
DISPLAY 0.680851 (-7025 3300);
PAINT MONO (-7025 3300);
DISPLAY INVISIBLE (-7025 3300);
FORCEPROP 2 LAST CDS_SEC 1
J 0
(-7025 3300);
DISPLAY 1.021277 (-7025 3300);
DISPLAY INVISIBLE (-7025 3300);
FORCEADD UNIVERSAL_POWER..1
(-7075 3450);
FORCEPROP 3 LASTPIN (-7075 3400) SIG_NAME P3V3_DB2000_VDDA\g
J 0
(-7065 3410);
DISPLAY 0.659574 (-7065 3410);
PAINT MONO (-7065 3410);
DISPLAY INVISIBLE (-7065 3410);
FORCEPROP 1 LAST HDL_POWER P3V3_DB2000_VDDA
J 1
(-7075 3500);
DISPLAY 0.872340 (-7075 3500);
PAINT GREEN (-7075 3500);
FORCEPROP 2 LAST CDS_LIB logical_power
J 0
(-7075 3450);
PAINT MONO (-7075 3450);
DISPLAY INVISIBLE (-7075 3450);
FORCEPROP 1 LAST PATH I166
J 0
(-7025 3475);
DISPLAY 0.872340 (-7025 3475);
PAINT AQUA (-7025 3475);
DISPLAY INVISIBLE (-7025 3475);
FORCEADD Q_CAP..1
(-7450 3975);
FORCEPROP 1 LAST PART_NUMBER CH6101ME900
J 0
(-7400 3825);
DISPLAY 0.510638 (-7400 3825);
DISPLAY INVISIBLE (-7400 3825);
FORCEPROP 1 LAST TOLERANCE 20%
J 0
(-7400 3925);
DISPLAY 0.510638 (-7400 3925);
FORCEPROP 1 LAST VALUE 10UF
J 0
(-7400 4025);
DISPLAY 0.510638 (-7400 4025);
FORCEPROP 1 LAST MATERIAL X6S
J 0
(-7400 3875);
DISPLAY 0.510638 (-7400 3875);
FORCEPROP 1 LAST VOLTAGE 6.3V
J 0
(-7400 3975);
DISPLAY 0.510638 (-7400 3975);
FORCEPROP 1 LAST PACK_TYPE C0603
J 0
(-7400 3775);
DISPLAY 0.510638 (-7400 3775);
FORCEPROP 1 LAST $LOCATION C208
J 0
(-7400 4075);
DISPLAY 0.978723 (-7400 4075);
FORCEPROP 1 LASTPIN (-7450 4075) $PN 1
J 0
(-7440 4055);
DISPLAY 0.787234 (-7440 4055);
FORCEPROP 1 LASTPIN (-7450 3875) $PN 2
J 0
(-7440 3855);
DISPLAY 0.787234 (-7440 3855);
FORCEPROP 1 LAST PATH I167
J 0
(-7400 4125);
DISPLAY 0.978723 (-7400 4125);
PAINT WHITE (-7400 4125);
DISPLAY INVISIBLE (-7400 4125);
FORCEPROP 2 LAST CDS_LIB pure_quanta
J 0
(-7450 3975);
PAINT MONO (-7450 3975);
DISPLAY INVISIBLE (-7450 3975);
FORCEPROP 2 LAST CDS_LOCATION C208
J 0
(-7400 4175);
DISPLAY 1.021277 (-7400 4175);
DISPLAY INVISIBLE (-7400 4175);
FORCEPROP 2 LAST $SEC 1
J 0
(-7400 4175);
DISPLAY 0.680851 (-7400 4175);
PAINT MONO (-7400 4175);
DISPLAY INVISIBLE (-7400 4175);
FORCEPROP 2 LAST CDS_SEC 1
J 0
(-7400 4175);
DISPLAY 1.021277 (-7400 4175);
DISPLAY INVISIBLE (-7400 4175);
FORCEADD Q_CAP..1
(-7075 3975);
FORCEPROP 1 LAST PART_NUMBER CH4104K1B00
J 0
(-7025 3825);
DISPLAY 0.617021 (-7025 3825);
DISPLAY INVISIBLE (-7025 3825);
FORCEPROP 1 LAST MATERIAL X7R
J 0
(-7025 3875);
DISPLAY 0.617021 (-7025 3875);
FORCEPROP 1 LAST TOLERANCE 10%
J 0
(-7025 3925);
DISPLAY 0.617021 (-7025 3925);
FORCEPROP 1 LAST VALUE 0.1UF
J 0
(-7025 4025);
DISPLAY 0.617021 (-7025 4025);
FORCEPROP 1 LAST VOLTAGE 25V
J 0
(-7025 3975);
DISPLAY 0.617021 (-7025 3975);
FORCEPROP 1 LAST PACK_TYPE 0402
J 0
(-7025 3775);
DISPLAY 0.617021 (-7025 3775);
FORCEPROP 1 LAST $LOCATION C210
J 0
(-7025 4075);
DISPLAY 0.978723 (-7025 4075);
FORCEPROP 1 LASTPIN (-7075 4075) $PN 1
J 0
(-7065 4055);
DISPLAY 0.787234 (-7065 4055);
FORCEPROP 1 LASTPIN (-7075 3875) $PN 2
J 0
(-7065 3855);
DISPLAY 0.787234 (-7065 3855);
FORCEPROP 2 LAST BOM_COST VR_SYSTEM 
J 0
(-7025 4125);
DISPLAY 0.680851 (-7025 4125);
DISPLAY INVISIBLE (-7025 4125);
FORCEPROP 2 LAST CDS_LIB pure_quanta
J 0
(-7075 3975);
PAINT MONO (-7075 3975);
DISPLAY INVISIBLE (-7075 3975);
FORCEPROP 1 LAST PATH I168
J 0
(-7025 4125);
DISPLAY 0.978723 (-7025 4125);
PAINT WHITE (-7025 4125);
DISPLAY INVISIBLE (-7025 4125);
FORCEPROP 2 LAST CDS_LOCATION C210
J 0
(-7025 4175);
DISPLAY 1.021277 (-7025 4175);
DISPLAY INVISIBLE (-7025 4175);
FORCEPROP 2 LAST $SEC 1
J 0
(-7025 4175);
DISPLAY 0.680851 (-7025 4175);
PAINT MONO (-7025 4175);
DISPLAY INVISIBLE (-7025 4175);
FORCEPROP 2 LAST CDS_SEC 1
J 0
(-7025 4175);
DISPLAY 1.021277 (-7025 4175);
DISPLAY INVISIBLE (-7025 4175);
FORCEADD UNIVERSAL_POWER..1
(-7075 4325);
FORCEPROP 3 LASTPIN (-7075 4275) SIG_NAME P3V3_DB2000_VDDR\g
J 0
(-7065 4285);
DISPLAY 0.659574 (-7065 4285);
PAINT MONO (-7065 4285);
DISPLAY INVISIBLE (-7065 4285);
FORCEPROP 1 LAST HDL_POWER P3V3_DB2000_VDDR
J 1
(-7075 4375);
DISPLAY 0.872340 (-7075 4375);
PAINT GREEN (-7075 4375);
FORCEPROP 2 LAST CDS_LIB logical_power
J 0
(-7075 4325);
PAINT MONO (-7075 4325);
DISPLAY INVISIBLE (-7075 4325);
FORCEPROP 1 LAST PATH I169
J 0
(-7025 4350);
DISPLAY 0.872340 (-7025 4350);
PAINT AQUA (-7025 4350);
DISPLAY INVISIBLE (-7025 4350);
FORCEADD Q_INDUCTOR..1
(-9100 5250);
FORCEPROP 1 LAST PART_NUMBER CX8SG331000
J 0
(-9225 5360);
DISPLAY 0.723404 (-9225 5360);
PAINT GREEN (-9225 5360);
DISPLAY INVISIBLE (-9225 5360);
FORCEPROP 2 LAST VALUE BLM18SG331TN1D/1.5A
J 0
(-9225 5400);
DISPLAY 0.808511 (-9225 5400);
FORCEPROP 2 LAST PACK_TYPE SMLF
J 0
(-9225 5450);
DISPLAY 0.808511 (-9225 5450);
FORCEPROP 1 LAST MATERIAL IND
J 0
(-9225 5305);
DISPLAY 0.723404 (-9225 5305);
PAINT GREEN (-9225 5305);
FORCEPROP 1 LAST $LOCATION L3
J 0
(-9325 5235);
DISPLAY 0.723404 (-9325 5235);
PAINT GREEN (-9325 5235);
FORCEPROP 2 LASTPIN (-9200 5225) $PN 1
J 2
(-9210 5235);
DISPLAY 0.808511 (-9210 5235);
FORCEPROP 2 LASTPIN (-9000 5225) $PN 2
J 0
(-8990 5235);
DISPLAY 0.808511 (-8990 5235);
FORCEPROP 2 LAST CDS_LIB pure_quanta
J 0
(-9100 5250);
PAINT MONO (-9100 5250);
DISPLAY INVISIBLE (-9100 5250);
FORCEPROP 1 LAST NEEDS_NO_SIZE TRUE
J 0
(-9100 5250);
DISPLAY 0.468085 (-9100 5250);
PAINT GREEN (-9100 5250);
DISPLAY INVISIBLE (-9100 5250);
FORCEPROP 1 LAST PATH I170
J 0
(-9025 5305);
DISPLAY 0.723404 (-9025 5305);
PAINT GREEN (-9025 5305);
DISPLAY INVISIBLE (-9025 5305);
FORCEPROP 2 LAST CDS_LOCATION L3
J 0
(-9225 5500);
DISPLAY 1.021277 (-9225 5500);
DISPLAY INVISIBLE (-9225 5500);
FORCEPROP 2 LAST $SEC 1
J 0
(-9225 5500);
DISPLAY 0.680851 (-9225 5500);
PAINT MONO (-9225 5500);
DISPLAY INVISIBLE (-9225 5500);
FORCEPROP 2 LAST CDS_SEC 1
J 0
(-9225 5500);
DISPLAY 1.021277 (-9225 5500);
DISPLAY INVISIBLE (-9225 5500);
FORCEADD Q_CAP..1
(-8875 5000);
FORCEPROP 1 LAST PART_NUMBER CH4104K1B00
J 0
(-8825 4850);
DISPLAY 0.617021 (-8825 4850);
DISPLAY INVISIBLE (-8825 4850);
FORCEPROP 1 LAST PACK_TYPE 0402
J 0
(-8825 4800);
DISPLAY 0.617021 (-8825 4800);
FORCEPROP 1 LAST MATERIAL X7R
J 0
(-8825 4900);
DISPLAY 0.617021 (-8825 4900);
FORCEPROP 1 LAST TOLERANCE 10%
J 0
(-8825 4950);
DISPLAY 0.617021 (-8825 4950);
FORCEPROP 1 LAST VOLTAGE 25V
J 0
(-8825 5000);
DISPLAY 0.617021 (-8825 5000);
FORCEPROP 1 LAST VALUE 0.1UF
J 0
(-8825 5050);
DISPLAY 0.617021 (-8825 5050);
FORCEPROP 1 LAST $LOCATION C204
J 0
(-8825 5100);
DISPLAY 0.978723 (-8825 5100);
FORCEPROP 1 LASTPIN (-8875 5100) $PN 1
J 0
(-8865 5080);
DISPLAY 0.787234 (-8865 5080);
FORCEPROP 1 LASTPIN (-8875 4900) $PN 2
J 0
(-8865 4880);
DISPLAY 0.787234 (-8865 4880);
FORCEPROP 2 LAST CDS_LIB pure_quanta
J 2
(-8875 5000);
PAINT MONO (-8875 5000);
DISPLAY INVISIBLE (-8875 5000);
FORCEPROP 2 LAST BOM_COST VR_SYSTEM 
J 0
(-8825 5150);
DISPLAY 0.680851 (-8825 5150);
DISPLAY INVISIBLE (-8825 5150);
FORCEPROP 1 LAST PATH I171
J 0
(-8825 5150);
DISPLAY 0.978723 (-8825 5150);
PAINT WHITE (-8825 5150);
DISPLAY INVISIBLE (-8825 5150);
FORCEPROP 2 LAST CDS_LOCATION C204
J 0
(-8825 5200);
DISPLAY 1.021277 (-8825 5200);
DISPLAY INVISIBLE (-8825 5200);
FORCEPROP 2 LAST $SEC 1
J 0
(-8825 5200);
DISPLAY 0.680851 (-8825 5200);
PAINT MONO (-8825 5200);
DISPLAY INVISIBLE (-8825 5200);
FORCEPROP 2 LAST CDS_SEC 1
J 0
(-8825 5200);
DISPLAY 1.021277 (-8825 5200);
DISPLAY INVISIBLE (-8825 5200);
FORCEADD Q_CAP..1
(-8475 5000);
FORCEPROP 1 LAST PART_NUMBER CH4104K1B00
J 0
(-8425 4850);
DISPLAY 0.617021 (-8425 4850);
DISPLAY INVISIBLE (-8425 4850);
FORCEPROP 1 LAST VALUE 0.1UF
J 0
(-8425 5050);
DISPLAY 0.617021 (-8425 5050);
FORCEPROP 1 LAST PACK_TYPE 0402
J 0
(-8425 4800);
DISPLAY 0.617021 (-8425 4800);
FORCEPROP 1 LAST TOLERANCE 10%
J 0
(-8425 4950);
DISPLAY 0.617021 (-8425 4950);
FORCEPROP 1 LAST MATERIAL X7R
J 0
(-8425 4900);
DISPLAY 0.617021 (-8425 4900);
FORCEPROP 1 LAST VOLTAGE 25V
J 0
(-8425 5000);
DISPLAY 0.617021 (-8425 5000);
FORCEPROP 1 LAST $LOCATION C205
J 0
(-8425 5100);
DISPLAY 0.978723 (-8425 5100);
FORCEPROP 1 LASTPIN (-8475 5100) $PN 1
J 0
(-8465 5080);
DISPLAY 0.787234 (-8465 5080);
FORCEPROP 1 LASTPIN (-8475 4900) $PN 2
J 0
(-8465 4880);
DISPLAY 0.787234 (-8465 4880);
FORCEPROP 2 LAST CDS_LIB pure_quanta
J 0
(-8475 5000);
PAINT MONO (-8475 5000);
DISPLAY INVISIBLE (-8475 5000);
FORCEPROP 2 LAST BOM_COST VR_SYSTEM 
J 0
(-8425 5150);
DISPLAY 0.680851 (-8425 5150);
DISPLAY INVISIBLE (-8425 5150);
FORCEPROP 1 LAST PATH I172
J 0
(-8425 5150);
DISPLAY 0.978723 (-8425 5150);
PAINT WHITE (-8425 5150);
DISPLAY INVISIBLE (-8425 5150);
FORCEPROP 2 LAST CDS_LOCATION C205
J 0
(-8425 5200);
DISPLAY 1.021277 (-8425 5200);
DISPLAY INVISIBLE (-8425 5200);
FORCEPROP 2 LAST $SEC 1
J 0
(-8425 5200);
DISPLAY 0.680851 (-8425 5200);
PAINT MONO (-8425 5200);
DISPLAY INVISIBLE (-8425 5200);
FORCEPROP 2 LAST CDS_SEC 1
J 0
(-8425 5200);
DISPLAY 1.021277 (-8425 5200);
DISPLAY INVISIBLE (-8425 5200);
FORCEADD Q_CAP..1
(-8100 5000);
FORCEPROP 1 LAST PART_NUMBER CH4104K1B00
J 0
(-8050 4850);
DISPLAY 0.617021 (-8050 4850);
DISPLAY INVISIBLE (-8050 4850);
FORCEPROP 1 LAST MATERIAL X7R
J 0
(-8050 4900);
DISPLAY 0.617021 (-8050 4900);
FORCEPROP 1 LAST VOLTAGE 25V
J 0
(-8050 5000);
DISPLAY 0.617021 (-8050 5000);
FORCEPROP 1 LAST VALUE 0.1UF
J 0
(-8050 5050);
DISPLAY 0.617021 (-8050 5050);
FORCEPROP 1 LAST PACK_TYPE 0402
J 0
(-8050 4800);
DISPLAY 0.617021 (-8050 4800);
FORCEPROP 1 LAST TOLERANCE 10%
J 0
(-8050 4950);
DISPLAY 0.617021 (-8050 4950);
FORCEPROP 1 LAST $LOCATION C206
J 0
(-8050 5100);
DISPLAY 0.978723 (-8050 5100);
FORCEPROP 1 LASTPIN (-8100 5100) $PN 1
J 0
(-8090 5080);
DISPLAY 0.787234 (-8090 5080);
FORCEPROP 1 LASTPIN (-8100 4900) $PN 2
J 0
(-8090 4880);
DISPLAY 0.787234 (-8090 4880);
FORCEPROP 2 LAST CDS_LIB pure_quanta
J 0
(-8100 5000);
PAINT MONO (-8100 5000);
DISPLAY INVISIBLE (-8100 5000);
FORCEPROP 2 LAST BOM_COST VR_SYSTEM 
J 0
(-8050 5150);
DISPLAY 0.680851 (-8050 5150);
DISPLAY INVISIBLE (-8050 5150);
FORCEPROP 1 LAST PATH I173
J 0
(-8050 5150);
DISPLAY 0.978723 (-8050 5150);
PAINT WHITE (-8050 5150);
DISPLAY INVISIBLE (-8050 5150);
FORCEPROP 2 LAST CDS_LOCATION C206
J 0
(-8050 5200);
DISPLAY 1.021277 (-8050 5200);
DISPLAY INVISIBLE (-8050 5200);
FORCEPROP 2 LAST $SEC 1
J 0
(-8050 5200);
DISPLAY 0.680851 (-8050 5200);
PAINT MONO (-8050 5200);
DISPLAY INVISIBLE (-8050 5200);
FORCEPROP 2 LAST CDS_SEC 1
J 0
(-8050 5200);
DISPLAY 1.021277 (-8050 5200);
DISPLAY INVISIBLE (-8050 5200);
FORCEADD Q_CAP..1
(-7725 5000);
FORCEPROP 1 LAST PART_NUMBER CH4104K1B00
J 0
(-7675 4850);
DISPLAY 0.617021 (-7675 4850);
DISPLAY INVISIBLE (-7675 4850);
FORCEPROP 1 LAST VOLTAGE 25V
J 0
(-7675 5000);
DISPLAY 0.617021 (-7675 5000);
FORCEPROP 1 LAST VALUE 0.1UF
J 0
(-7675 5050);
DISPLAY 0.617021 (-7675 5050);
FORCEPROP 1 LAST MATERIAL X7R
J 0
(-7675 4900);
DISPLAY 0.617021 (-7675 4900);
FORCEPROP 1 LAST TOLERANCE 10%
J 0
(-7675 4950);
DISPLAY 0.617021 (-7675 4950);
FORCEPROP 1 LAST PACK_TYPE 0402
J 0
(-7675 4800);
DISPLAY 0.617021 (-7675 4800);
FORCEPROP 1 LAST $LOCATION C207
J 0
(-7675 5100);
DISPLAY 0.978723 (-7675 5100);
FORCEPROP 1 LASTPIN (-7725 5100) $PN 1
J 0
(-7715 5080);
DISPLAY 0.787234 (-7715 5080);
FORCEPROP 1 LASTPIN (-7725 4900) $PN 2
J 0
(-7715 4880);
DISPLAY 0.787234 (-7715 4880);
FORCEPROP 2 LAST BOM_COST VR_SYSTEM 
J 0
(-7675 5150);
DISPLAY 0.680851 (-7675 5150);
DISPLAY INVISIBLE (-7675 5150);
FORCEPROP 2 LAST CDS_LIB pure_quanta
J 0
(-7725 5000);
PAINT MONO (-7725 5000);
DISPLAY INVISIBLE (-7725 5000);
FORCEPROP 1 LAST PATH I174
J 0
(-7675 5150);
DISPLAY 0.978723 (-7675 5150);
PAINT WHITE (-7675 5150);
DISPLAY INVISIBLE (-7675 5150);
FORCEPROP 2 LAST CDS_LOCATION C207
J 0
(-7675 5200);
DISPLAY 1.021277 (-7675 5200);
DISPLAY INVISIBLE (-7675 5200);
FORCEPROP 2 LAST $SEC 1
J 0
(-7675 5200);
DISPLAY 0.680851 (-7675 5200);
PAINT MONO (-7675 5200);
DISPLAY INVISIBLE (-7675 5200);
FORCEPROP 2 LAST CDS_SEC 1
J 0
(-7675 5200);
DISPLAY 1.021277 (-7675 5200);
DISPLAY INVISIBLE (-7675 5200);
FORCEADD UNIVERSAL_POWER..1
(-7300 5500);
FORCEPROP 3 LASTPIN (-7300 5450) SIG_NAME P3V3_DB2000_VDD\g
J 0
(-7290 5460);
DISPLAY 0.659574 (-7290 5460);
PAINT MONO (-7290 5460);
DISPLAY INVISIBLE (-7290 5460);
FORCEPROP 1 LAST HDL_POWER P3V3_DB2000_VDD
J 1
(-7300 5550);
DISPLAY 0.872340 (-7300 5550);
PAINT GREEN (-7300 5550);
FORCEPROP 2 LAST CDS_LIB logical_power
J 0
(-7300 5500);
PAINT MONO (-7300 5500);
DISPLAY INVISIBLE (-7300 5500);
FORCEPROP 1 LAST PATH I175
J 0
(-7250 5525);
DISPLAY 0.872340 (-7250 5525);
PAINT AQUA (-7250 5525);
DISPLAY INVISIBLE (-7250 5525);
FORCEADD UNIVERSAL_POWER..1
(-9425 5525);
FORCEPROP 3 LASTPIN (-9425 5475) SIG_NAME P3V3\g
J 0
(-9415 5485);
DISPLAY 0.659574 (-9415 5485);
PAINT MONO (-9415 5485);
DISPLAY INVISIBLE (-9415 5485);
FORCEPROP 1 LAST HDL_POWER P3V3
J 1
(-9425 5575);
DISPLAY 0.872340 (-9425 5575);
PAINT GREEN (-9425 5575);
FORCEPROP 2 LAST CDS_LIB logical_power
J 0
(-9425 5525);
PAINT MONO (-9425 5525);
DISPLAY INVISIBLE (-9425 5525);
FORCEPROP 1 LAST PATH I176
J 0
(-9375 5550);
DISPLAY 0.872340 (-9375 5550);
PAINT AQUA (-9375 5550);
DISPLAY INVISIBLE (-9375 5550);
FORCEADD Q_INDUCTOR..1
(-9100 4225);
FORCEPROP 1 LAST PART_NUMBER CX8SG331000
J 0
(-9225 4335);
DISPLAY 0.723404 (-9225 4335);
PAINT GREEN (-9225 4335);
DISPLAY INVISIBLE (-9225 4335);
FORCEPROP 2 LAST VALUE BLM18SG331TN1D/1.5A
J 0
(-9225 4375);
DISPLAY 0.808511 (-9225 4375);
FORCEPROP 2 LAST PACK_TYPE SMLF
J 0
(-9225 4425);
DISPLAY 0.808511 (-9225 4425);
FORCEPROP 1 LAST MATERIAL IND
J 0
(-9225 4280);
DISPLAY 0.723404 (-9225 4280);
PAINT GREEN (-9225 4280);
FORCEPROP 1 LAST $LOCATION L4
J 0
(-9325 4210);
DISPLAY 0.723404 (-9325 4210);
PAINT GREEN (-9325 4210);
FORCEPROP 2 LASTPIN (-9200 4200) $PN 1
J 2
(-9210 4210);
DISPLAY 0.808511 (-9210 4210);
FORCEPROP 2 LASTPIN (-9000 4200) $PN 2
J 0
(-8990 4210);
DISPLAY 0.808511 (-8990 4210);
FORCEPROP 2 LAST CDS_LIB pure_quanta
J 0
(-9100 4225);
PAINT MONO (-9100 4225);
DISPLAY INVISIBLE (-9100 4225);
FORCEPROP 1 LAST NEEDS_NO_SIZE TRUE
J 0
(-9100 4225);
DISPLAY 0.468085 (-9100 4225);
PAINT GREEN (-9100 4225);
DISPLAY INVISIBLE (-9100 4225);
FORCEPROP 1 LAST PATH I177
J 0
(-9025 4280);
DISPLAY 0.723404 (-9025 4280);
PAINT GREEN (-9025 4280);
DISPLAY INVISIBLE (-9025 4280);
FORCEPROP 2 LAST CDS_LOCATION L4
J 0
(-9225 4475);
DISPLAY 1.021277 (-9225 4475);
DISPLAY INVISIBLE (-9225 4475);
FORCEPROP 2 LAST $SEC 1
J 0
(-9225 4475);
DISPLAY 0.680851 (-9225 4475);
PAINT MONO (-9225 4475);
DISPLAY INVISIBLE (-9225 4475);
FORCEPROP 2 LAST CDS_SEC 1
J 0
(-9225 4475);
DISPLAY 1.021277 (-9225 4475);
DISPLAY INVISIBLE (-9225 4475);
FORCEADD Q_RES..2
(-9225 1475);
FORCEPROP 1 LAST PART_NUMBER CS24702FB06
J 0
(-9185 1350);
DISPLAY 0.638298 (-9185 1350);
DISPLAY INVISIBLE (-9185 1350);
FORCEPROP 1 LAST MATERIAL CHIP
J 0
(-9185 1400);
DISPLAY 0.638298 (-9185 1400);
FORCEPROP 1 LAST PACK_TYPE 0402LF
J 0
(-9185 1300);
DISPLAY 0.638298 (-9185 1300);
FORCEPROP 1 LAST WATTAGE 1/16W
J 0
(-9185 1450);
DISPLAY 0.638298 (-9185 1450);
FORCEPROP 1 LAST TOLERANCE 1%
J 0
(-9180 1500);
DISPLAY 0.638298 (-9180 1500);
FORCEPROP 1 LAST VALUE 4.7K
J 0
(-9180 1550);
DISPLAY 0.638298 (-9180 1550);
FORCEPROP 1 LAST $LOCATION R568
J 0
(-9180 1600);
DISPLAY 0.978723 (-9180 1600);
FORCEPROP 1 LASTPIN (-9225 1575) $PN 1
J 0
(-9220 1537);
DISPLAY 0.787234 (-9220 1537);
FORCEPROP 1 LASTPIN (-9225 1375) $PN 2
J 0
(-9220 1385);
DISPLAY 0.787234 (-9220 1385);
FORCEPROP 1 LAST PATH I178
J 0
(-9175 1650);
DISPLAY 0.978723 (-9175 1650);
PAINT WHITE (-9175 1650);
DISPLAY INVISIBLE (-9175 1650);
FORCEPROP 2 LAST CDS_LIB pure_quanta
J 0
(-9225 1475);
PAINT MONO (-9225 1475);
DISPLAY INVISIBLE (-9225 1475);
FORCEPROP 2 LAST CDS_LOCATION R568
J 0
(-9175 1700);
DISPLAY 1.021277 (-9175 1700);
DISPLAY INVISIBLE (-9175 1700);
FORCEPROP 2 LAST $SEC 1
J 0
(-9175 1700);
DISPLAY 0.680851 (-9175 1700);
PAINT MONO (-9175 1700);
DISPLAY INVISIBLE (-9175 1700);
FORCEPROP 2 LAST CDS_SEC 1
J 0
(-9175 1700);
DISPLAY 1.021277 (-9175 1700);
DISPLAY INVISIBLE (-9175 1700);
FORCEADD Q_RES..2
(-9225 2050);
FORCEPROP 1 LAST PART_NUMBER CS24702FB06
J 0
(-9185 1925);
DISPLAY 0.638298 (-9185 1925);
DISPLAY INVISIBLE (-9185 1925);
FORCEPROP 1 LAST MATERIAL EMPTY
J 0
(-9185 1975);
DISPLAY 0.638298 (-9185 1975);
PAINT RED (-9185 1975);
FORCEPROP 1 LAST TOLERANCE 1%
J 0
(-9180 2075);
DISPLAY 0.638298 (-9180 2075);
FORCEPROP 1 LAST PACK_TYPE 0402LF
J 0
(-9185 1875);
DISPLAY 0.638298 (-9185 1875);
FORCEPROP 1 LAST WATTAGE 1/16W
J 0
(-9185 2025);
DISPLAY 0.638298 (-9185 2025);
FORCEPROP 1 LAST VALUE 4.7K
J 0
(-9180 2125);
DISPLAY 0.638298 (-9180 2125);
FORCEPROP 1 LAST $LOCATION R567
J 0
(-9180 2175);
DISPLAY 0.978723 (-9180 2175);
FORCEPROP 1 LASTPIN (-9225 2150) $PN 1
J 0
(-9220 2112);
DISPLAY 0.787234 (-9220 2112);
FORCEPROP 1 LASTPIN (-9225 1950) $PN 2
J 0
(-9220 1960);
DISPLAY 0.787234 (-9220 1960);
FORCEPROP 1 LAST PATH I179
J 0
(-9175 2225);
DISPLAY 0.978723 (-9175 2225);
PAINT WHITE (-9175 2225);
DISPLAY INVISIBLE (-9175 2225);
FORCEPROP 2 LAST CDS_LIB pure_quanta
J 0
(-9225 2050);
PAINT MONO (-9225 2050);
DISPLAY INVISIBLE (-9225 2050);
FORCEPROP 2 LAST CDS_LOCATION R567
J 0
(-9175 2275);
DISPLAY 1.021277 (-9175 2275);
DISPLAY INVISIBLE (-9175 2275);
FORCEPROP 2 LAST $SEC 1
J 0
(-9175 2275);
DISPLAY 0.680851 (-9175 2275);
PAINT MONO (-9175 2275);
DISPLAY INVISIBLE (-9175 2275);
FORCEPROP 2 LAST CDS_SEC 1
J 0
(-9175 2275);
DISPLAY 1.021277 (-9175 2275);
DISPLAY INVISIBLE (-9175 2275);
FORCEADD UNIVERSAL_POWER..1
(-9225 2375);
FORCEPROP 3 LASTPIN (-9225 2325) SIG_NAME P3V3\g
J 0
(-9215 2335);
DISPLAY 0.659574 (-9215 2335);
PAINT MONO (-9215 2335);
DISPLAY INVISIBLE (-9215 2335);
FORCEPROP 1 LAST HDL_POWER P3V3
J 1
(-9225 2425);
DISPLAY 0.872340 (-9225 2425);
PAINT GREEN (-9225 2425);
FORCEPROP 1 LAST PATH I183
J 0
(-9175 2400);
DISPLAY 0.872340 (-9175 2400);
PAINT AQUA (-9175 2400);
DISPLAY INVISIBLE (-9175 2400);
FORCEPROP 2 LAST CDS_LIB logical_power
J 0
(-9225 2375);
PAINT MONO (-9225 2375);
DISPLAY INVISIBLE (-9225 2375);
FORCEADD Q_RES..2
(-8825 2050);
FORCEPROP 1 LAST PART_NUMBER CS24702FB06
J 0
(-8785 1925);
DISPLAY 0.638298 (-8785 1925);
DISPLAY INVISIBLE (-8785 1925);
FORCEPROP 1 LAST MATERIAL EMPTY
J 0
(-8785 1975);
DISPLAY 0.638298 (-8785 1975);
PAINT RED (-8785 1975);
FORCEPROP 1 LAST PACK_TYPE 0402LF
J 0
(-8785 1875);
DISPLAY 0.638298 (-8785 1875);
FORCEPROP 1 LAST TOLERANCE 1%
J 0
(-8780 2075);
DISPLAY 0.638298 (-8780 2075);
FORCEPROP 1 LAST WATTAGE 1/16W
J 0
(-8785 2025);
DISPLAY 0.638298 (-8785 2025);
FORCEPROP 1 LAST VALUE 4.7K
J 0
(-8780 2125);
DISPLAY 0.638298 (-8780 2125);
FORCEPROP 1 LAST $LOCATION R569
J 0
(-8780 2175);
DISPLAY 0.978723 (-8780 2175);
FORCEPROP 1 LASTPIN (-8825 2150) $PN 1
J 0
(-8820 2112);
DISPLAY 0.787234 (-8820 2112);
FORCEPROP 1 LASTPIN (-8825 1950) $PN 2
J 0
(-8820 1960);
DISPLAY 0.787234 (-8820 1960);
FORCEPROP 1 LAST PATH I185
J 0
(-8775 2225);
DISPLAY 0.978723 (-8775 2225);
PAINT WHITE (-8775 2225);
DISPLAY INVISIBLE (-8775 2225);
FORCEPROP 2 LAST CDS_LIB pure_quanta
J 0
(-8825 2050);
PAINT MONO (-8825 2050);
DISPLAY INVISIBLE (-8825 2050);
FORCEPROP 2 LAST CDS_LOCATION R569
J 0
(-8775 2275);
DISPLAY 1.021277 (-8775 2275);
DISPLAY INVISIBLE (-8775 2275);
FORCEPROP 2 LAST $SEC 1
J 0
(-8775 2275);
DISPLAY 0.680851 (-8775 2275);
PAINT MONO (-8775 2275);
DISPLAY INVISIBLE (-8775 2275);
FORCEPROP 2 LAST CDS_SEC 1
J 0
(-8775 2275);
DISPLAY 1.021277 (-8775 2275);
DISPLAY INVISIBLE (-8775 2275);
FORCEADD Q_RES..2
(-8825 1475);
FORCEPROP 1 LAST PART_NUMBER CS24702FB06
J 0
(-8785 1350);
DISPLAY 0.638298 (-8785 1350);
DISPLAY INVISIBLE (-8785 1350);
FORCEPROP 1 LAST TOLERANCE 1%
J 0
(-8780 1500);
DISPLAY 0.638298 (-8780 1500);
FORCEPROP 1 LAST WATTAGE 1/16W
J 0
(-8785 1450);
DISPLAY 0.638298 (-8785 1450);
FORCEPROP 1 LAST MATERIAL CHIP
J 0
(-8785 1400);
DISPLAY 0.638298 (-8785 1400);
FORCEPROP 1 LAST PACK_TYPE 0402LF
J 0
(-8785 1300);
DISPLAY 0.638298 (-8785 1300);
FORCEPROP 1 LAST VALUE 4.7K
J 0
(-8780 1550);
DISPLAY 0.638298 (-8780 1550);
FORCEPROP 1 LAST $LOCATION R570
J 0
(-8780 1600);
DISPLAY 0.978723 (-8780 1600);
FORCEPROP 1 LASTPIN (-8825 1575) $PN 1
J 0
(-8820 1537);
DISPLAY 0.787234 (-8820 1537);
FORCEPROP 1 LASTPIN (-8825 1375) $PN 2
J 0
(-8820 1385);
DISPLAY 0.787234 (-8820 1385);
FORCEPROP 1 LAST PATH I187
J 0
(-8775 1650);
DISPLAY 0.978723 (-8775 1650);
PAINT WHITE (-8775 1650);
DISPLAY INVISIBLE (-8775 1650);
FORCEPROP 2 LAST CDS_LIB pure_quanta
J 0
(-8825 1475);
PAINT MONO (-8825 1475);
DISPLAY INVISIBLE (-8825 1475);
FORCEPROP 2 LAST CDS_LOCATION R570
J 0
(-8775 1700);
DISPLAY 1.021277 (-8775 1700);
DISPLAY INVISIBLE (-8775 1700);
FORCEPROP 2 LAST $SEC 1
J 0
(-8775 1700);
DISPLAY 0.680851 (-8775 1700);
PAINT MONO (-8775 1700);
DISPLAY INVISIBLE (-8775 1700);
FORCEPROP 2 LAST CDS_SEC 1
J 0
(-8775 1700);
DISPLAY 1.021277 (-8775 1700);
DISPLAY INVISIBLE (-8775 1700);
FORCEADD OFFPAGE..1
(-4875 3400);
FORCEPROP 2 LAST $XR0 206 
J 0
(-5157 3400);
DISPLAY 0.638298 (-5157 3400);
PAINT MONO (-5157 3400);
FORCEPROP 1 LAST COMMENT_BODY TRUE
J 0
(-4750 3300);
DISPLAY 0.872340 (-4750 3300);
PAINT GREEN (-4750 3300);
DISPLAY INVISIBLE (-4750 3300);
FORCEPROP 1 LAST OFFPAGE TRUE
J 0
(-4550 3275);
DISPLAY 0.872340 (-4550 3275);
PAINT GREEN (-4550 3275);
DISPLAY INVISIBLE (-4550 3275);
FORCEPROP 2 LAST PATH I188
J 0
(-4825 3475);
DISPLAY 1.021277 (-4825 3475);
DISPLAY INVISIBLE (-4825 3475);
FORCEPROP 2 LAST CDS_LIB standard
J 0
(-4875 3400);
PAINT MONO (-4875 3400);
DISPLAY INVISIBLE (-4875 3400);
FORCEADD OFFPAGE..1
(-4875 3450);
FORCEPROP 2 LAST $XR0 206 
J 0
(-5157 3450);
DISPLAY 0.638298 (-5157 3450);
PAINT MONO (-5157 3450);
FORCEPROP 1 LAST COMMENT_BODY TRUE
J 0
(-4750 3350);
DISPLAY 0.872340 (-4750 3350);
PAINT GREEN (-4750 3350);
DISPLAY INVISIBLE (-4750 3350);
FORCEPROP 1 LAST OFFPAGE TRUE
J 0
(-4550 3325);
DISPLAY 0.872340 (-4550 3325);
PAINT GREEN (-4550 3325);
DISPLAY INVISIBLE (-4550 3325);
FORCEPROP 2 LAST PATH I189
J 0
(-4825 3525);
DISPLAY 1.021277 (-4825 3525);
DISPLAY INVISIBLE (-4825 3525);
FORCEPROP 2 LAST CDS_LIB standard
J 0
(-4875 3450);
PAINT MONO (-4875 3450);
DISPLAY INVISIBLE (-4875 3450);
FORCEADD OFFPAGE..2
(-8100 1800);
FORCEPROP 2 LAST $XR0 206 
J 0
(-7911 1800);
DISPLAY 0.638298 (-7911 1800);
PAINT MONO (-7911 1800);
FORCEPROP 1 LAST COMMENT_BODY TRUE
J 0
(-8145 1705);
DISPLAY 0.872340 (-8145 1705);
PAINT GREEN (-8145 1705);
DISPLAY INVISIBLE (-8145 1705);
FORCEPROP 1 LAST OFFPAGE TRUE
J 0
(-7775 1675);
DISPLAY 0.872340 (-7775 1675);
PAINT GREEN (-7775 1675);
DISPLAY INVISIBLE (-7775 1675);
FORCEPROP 2 LAST PATH I190
J 0
(-7925 1875);
DISPLAY 1.021277 (-7925 1875);
DISPLAY INVISIBLE (-7925 1875);
FORCEPROP 2 LAST CDS_LIB standard
J 0
(-8100 1800);
PAINT MONO (-8100 1800);
DISPLAY INVISIBLE (-8100 1800);
FORCEADD OFFPAGE..2
(-8100 1750);
FORCEPROP 2 LAST $XR0 206 
J 0
(-7911 1750);
DISPLAY 0.638298 (-7911 1750);
PAINT MONO (-7911 1750);
FORCEPROP 1 LAST COMMENT_BODY TRUE
J 0
(-8145 1655);
DISPLAY 0.872340 (-8145 1655);
PAINT GREEN (-8145 1655);
DISPLAY INVISIBLE (-8145 1655);
FORCEPROP 1 LAST OFFPAGE TRUE
J 0
(-7775 1625);
DISPLAY 0.872340 (-7775 1625);
PAINT GREEN (-7775 1625);
DISPLAY INVISIBLE (-7775 1625);
FORCEPROP 2 LAST CDS_LIB standard
J 0
(-8100 1750);
PAINT MONO (-8100 1750);
DISPLAY INVISIBLE (-8100 1750);
FORCEPROP 2 LAST PATH I191
J 0
(-7925 1825);
DISPLAY 1.021277 (-7925 1825);
DISPLAY INVISIBLE (-7925 1825);
FORCEADD OFFPAGE..2
(-8550 325);
FORCEPROP 2 LAST $XR0 206 
J 0
(-8361 325);
DISPLAY 0.638298 (-8361 325);
PAINT MONO (-8361 325);
FORCEPROP 1 LAST COMMENT_BODY TRUE
J 0
(-8595 230);
DISPLAY 0.872340 (-8595 230);
PAINT GREEN (-8595 230);
DISPLAY INVISIBLE (-8595 230);
FORCEPROP 1 LAST OFFPAGE TRUE
J 0
(-8225 200);
DISPLAY 0.872340 (-8225 200);
PAINT GREEN (-8225 200);
DISPLAY INVISIBLE (-8225 200);
FORCEPROP 2 LAST CDS_LIB standard
J 0
(-8550 325);
PAINT MONO (-8550 325);
DISPLAY INVISIBLE (-8550 325);
FORCEPROP 2 LAST PATH I192
J 0
(-8375 400);
DISPLAY 1.021277 (-8375 400);
DISPLAY INVISIBLE (-8375 400);
FORCEADD Q_RES..2
(-9225 625);
FORCEPROP 1 LAST PART_NUMBER CS24702FB06
J 0
(-9185 500);
DISPLAY 0.638298 (-9185 500);
DISPLAY INVISIBLE (-9185 500);
FORCEPROP 1 LAST TOLERANCE 1%
J 0
(-9180 650);
DISPLAY 0.638298 (-9180 650);
FORCEPROP 1 LAST MATERIAL EMPTY
J 0
(-9185 550);
DISPLAY 0.638298 (-9185 550);
PAINT RED (-9185 550);
FORCEPROP 1 LAST PACK_TYPE 0402LF
J 0
(-9185 450);
DISPLAY 0.638298 (-9185 450);
FORCEPROP 1 LAST WATTAGE 1/16W
J 0
(-9185 600);
DISPLAY 0.638298 (-9185 600);
FORCEPROP 1 LAST VALUE 4.7K
J 0
(-9180 700);
DISPLAY 0.638298 (-9180 700);
FORCEPROP 1 LAST $LOCATION R573
J 0
(-9180 750);
DISPLAY 0.978723 (-9180 750);
FORCEPROP 1 LASTPIN (-9225 725) $PN 1
J 0
(-9220 687);
DISPLAY 0.787234 (-9220 687);
FORCEPROP 1 LASTPIN (-9225 525) $PN 2
J 0
(-9220 535);
DISPLAY 0.787234 (-9220 535);
FORCEPROP 2 LAST CDS_LIB pure_quanta
J 0
(-9225 625);
PAINT MONO (-9225 625);
DISPLAY INVISIBLE (-9225 625);
FORCEPROP 1 LAST PATH I194
J 0
(-9175 800);
DISPLAY 0.978723 (-9175 800);
PAINT WHITE (-9175 800);
DISPLAY INVISIBLE (-9175 800);
FORCEPROP 2 LAST CDS_LOCATION R573
J 0
(-9175 850);
DISPLAY 1.021277 (-9175 850);
DISPLAY INVISIBLE (-9175 850);
FORCEPROP 2 LAST $SEC 1
J 0
(-9175 850);
DISPLAY 0.680851 (-9175 850);
PAINT MONO (-9175 850);
DISPLAY INVISIBLE (-9175 850);
FORCEPROP 2 LAST CDS_SEC 1
J 0
(-9175 850);
DISPLAY 1.021277 (-9175 850);
DISPLAY INVISIBLE (-9175 850);
FORCEADD UNIVERSAL_POWER..1
(-9225 900);
FORCEPROP 3 LASTPIN (-9225 850) SIG_NAME P3V3\g
J 0
(-9215 860);
DISPLAY 0.659574 (-9215 860);
PAINT MONO (-9215 860);
DISPLAY INVISIBLE (-9215 860);
FORCEPROP 1 LAST HDL_POWER P3V3
J 1
(-9225 950);
DISPLAY 0.872340 (-9225 950);
PAINT GREEN (-9225 950);
FORCEPROP 2 LAST CDS_LIB logical_power
J 0
(-9225 900);
PAINT MONO (-9225 900);
DISPLAY INVISIBLE (-9225 900);
FORCEPROP 1 LAST PATH I195
J 0
(-9175 925);
DISPLAY 0.872340 (-9175 925);
PAINT AQUA (-9175 925);
DISPLAY INVISIBLE (-9175 925);
FORCEADD Q_RES..2
(-9225 50);
FORCEPROP 1 LAST PART_NUMBER CS24702FB06
J 0
(-9185 -75);
DISPLAY 0.638298 (-9185 -75);
DISPLAY INVISIBLE (-9185 -75);
FORCEPROP 1 LAST TOLERANCE 1%
J 0
(-9180 75);
DISPLAY 0.638298 (-9180 75);
FORCEPROP 1 LAST VALUE 4.7K
J 0
(-9180 125);
DISPLAY 0.638298 (-9180 125);
FORCEPROP 1 LAST WATTAGE 1/16W
J 0
(-9185 25);
DISPLAY 0.638298 (-9185 25);
FORCEPROP 1 LAST MATERIAL CHIP
J 0
(-9185 -25);
DISPLAY 0.638298 (-9185 -25);
FORCEPROP 1 LAST PACK_TYPE 0402LF
J 0
(-9185 -125);
DISPLAY 0.638298 (-9185 -125);
FORCEPROP 1 LAST $LOCATION R574
J 0
(-9180 175);
DISPLAY 0.978723 (-9180 175);
FORCEPROP 1 LASTPIN (-9225 150) $PN 1
J 0
(-9220 112);
DISPLAY 0.787234 (-9220 112);
FORCEPROP 1 LASTPIN (-9225 -50) $PN 2
J 0
(-9220 -40);
DISPLAY 0.787234 (-9220 -40);
FORCEPROP 2 LAST CDS_LIB pure_quanta
J 0
(-9225 50);
PAINT MONO (-9225 50);
DISPLAY INVISIBLE (-9225 50);
FORCEPROP 1 LAST PATH I197
J 0
(-9175 225);
DISPLAY 0.978723 (-9175 225);
PAINT WHITE (-9175 225);
DISPLAY INVISIBLE (-9175 225);
FORCEPROP 2 LAST CDS_LOCATION R574
J 0
(-9175 275);
DISPLAY 1.021277 (-9175 275);
DISPLAY INVISIBLE (-9175 275);
FORCEPROP 2 LAST $SEC 1
J 0
(-9175 275);
DISPLAY 0.680851 (-9175 275);
PAINT MONO (-9175 275);
DISPLAY INVISIBLE (-9175 275);
FORCEPROP 2 LAST CDS_SEC 1
J 0
(-9175 275);
DISPLAY 1.021277 (-9175 275);
DISPLAY INVISIBLE (-9175 275);
FORCEADD Q_RES..1
(-5300 2550);
FORCEPROP 1 LAST PART_NUMBER CS04992FB07
J 0
(-5425 2625);
DISPLAY 0.510638 (-5425 2625);
DISPLAY INVISIBLE (-5425 2625);
FORCEPROP 1 LAST TOLERANCE 1%
J 0
(-5050 2550);
DISPLAY 0.510638 (-5050 2550);
FORCEPROP 1 LAST MATERIAL CHIP
J 0
(-4975 2550);
DISPLAY 0.510638 (-4975 2550);
FORCEPROP 1 LAST WATTAGE 1/16W
J 2
(-5125 2675);
DISPLAY 0.510638 (-5125 2675);
FORCEPROP 1 LAST VALUE 49.9
J 2
(-5100 2550);
DISPLAY 0.510638 (-5100 2550);
FORCEPROP 1 LAST PACK_TYPE 0402LF
J 0
(-5425 2675);
DISPLAY 0.510638 (-5425 2675);
FORCEPROP 1 LAST $LOCATION R575
J 0
(-5525 2550);
DISPLAY 0.510638 (-5525 2550);
FORCEPROP 1 LASTPIN (-5400 2550) $PN 1
J 0
(-5388 2562);
DISPLAY 0.787234 (-5388 2562);
FORCEPROP 1 LASTPIN (-5200 2550) $PN 2
J 0
(-5238 2562);
DISPLAY 0.787234 (-5238 2562);
FORCEPROP 1 LAST PATH I199
J 0
(-5350 2700);
DISPLAY 0.978723 (-5350 2700);
PAINT WHITE (-5350 2700);
DISPLAY INVISIBLE (-5350 2700);
FORCEPROP 2 LAST CDS_LIB pure_quanta
J 0
(-5300 2550);
PAINT MONO (-5300 2550);
DISPLAY INVISIBLE (-5300 2550);
FORCEPROP 2 LAST CDS_LOCATION R575
J 0
(-5350 2750);
DISPLAY 1.021277 (-5350 2750);
DISPLAY INVISIBLE (-5350 2750);
FORCEPROP 2 LAST $SEC 1
J 0
(-5350 2750);
DISPLAY 0.680851 (-5350 2750);
PAINT MONO (-5350 2750);
DISPLAY INVISIBLE (-5350 2750);
FORCEPROP 2 LAST CDS_SEC 1
J 0
(-5350 2750);
DISPLAY 1.021277 (-5350 2750);
DISPLAY INVISIBLE (-5350 2750);
FORCEADD OFFPAGE..1
(-6200 2575);
FORCEPROP 2 LAST $XR2 211 
J 0
(-6722 2575);
DISPLAY 0.638298 (-6722 2575);
PAINT MONO (-6722 2575);
FORCEPROP 2 LAST $XR1 223 
J 0
(-6602 2575);
DISPLAY 0.638298 (-6602 2575);
PAINT MONO (-6602 2575);
FORCEPROP 2 LAST $XR0 208 
J 0
(-6482 2575);
DISPLAY 0.638298 (-6482 2575);
PAINT MONO (-6482 2575);
FORCEPROP 2 LAST CDS_LIB standard
J 0
(-6200 2575);
PAINT MONO (-6200 2575);
DISPLAY INVISIBLE (-6200 2575);
FORCEPROP 1 LAST OFFPAGE TRUE
J 0
(-5875 2450);
DISPLAY 0.872340 (-5875 2450);
PAINT GREEN (-5875 2450);
DISPLAY INVISIBLE (-5875 2450);
FORCEPROP 1 LAST COMMENT_BODY TRUE
J 0
(-6075 2475);
DISPLAY 0.872340 (-6075 2475);
PAINT GREEN (-6075 2475);
DISPLAY INVISIBLE (-6075 2475);
FORCEPROP 2 LAST PATH I200
J 0
(-6150 2650);
DISPLAY 1.021277 (-6150 2650);
DISPLAY INVISIBLE (-6150 2650);
FORCEADD Q_RES..1
(-6225 2400);
FORCEPROP 1 LAST PART_NUMBER CS22002FB07
J 0
(-6375 2450);
DISPLAY 0.510638 (-6375 2450);
DISPLAY INVISIBLE (-6375 2450);
FORCEPROP 1 LAST WATTAGE 1/16W
J 2
(-6050 2500);
DISPLAY 0.510638 (-6050 2500);
FORCEPROP 1 LAST VALUE 2K
J 2
(-6025 2400);
DISPLAY 0.638298 (-6025 2400);
FORCEPROP 1 LAST TOLERANCE 1%
J 0
(-6000 2400);
DISPLAY 0.638298 (-6000 2400);
FORCEPROP 1 LAST MATERIAL CHIP
J 0
(-5900 2400);
DISPLAY 0.638298 (-5900 2400);
FORCEPROP 1 LAST PACK_TYPE 0402LF
J 0
(-6375 2500);
DISPLAY 0.510638 (-6375 2500);
FORCEPROP 1 LAST $LOCATION R106
J 0
(-6475 2400);
DISPLAY 0.638298 (-6475 2400);
FORCEPROP 1 LASTPIN (-6325 2400) $PN 1
J 0
(-6313 2412);
DISPLAY 0.787234 (-6313 2412);
FORCEPROP 1 LASTPIN (-6125 2400) $PN 2
J 0
(-6163 2412);
DISPLAY 0.787234 (-6163 2412);
FORCEPROP 2 LAST CDS_LIB pure_quanta
J 0
(-6225 2400);
PAINT MONO (-6225 2400);
DISPLAY INVISIBLE (-6225 2400);
FORCEPROP 1 LAST PATH I304
J 0
(-6275 2550);
DISPLAY 0.978723 (-6275 2550);
PAINT WHITE (-6275 2550);
DISPLAY INVISIBLE (-6275 2550);
FORCEPROP 2 LAST CDS_LOCATION R106
J 0
(-6275 2600);
DISPLAY 1.021277 (-6275 2600);
DISPLAY INVISIBLE (-6275 2600);
FORCEPROP 2 LAST $SEC 1
J 0
(-6275 2600);
DISPLAY 0.680851 (-6275 2600);
PAINT MONO (-6275 2600);
DISPLAY INVISIBLE (-6275 2600);
FORCEPROP 2 LAST CDS_SEC 1
J 0
(-6275 2600);
DISPLAY 1.021277 (-6275 2600);
DISPLAY INVISIBLE (-6275 2600);
FORCEADD OFFPAGE..2
(-1250 2900);
FORCEPROP 2 LAST $XR0 44 
J 0
(-1061 2900);
DISPLAY 0.638298 (-1061 2900);
PAINT MONO (-1061 2900);
FORCEPROP 2 LAST PATH I381
J 0
(-1050 2950);
DISPLAY 1.021277 (-1050 2950);
DISPLAY INVISIBLE (-1050 2950);
FORCEPROP 2 LAST CDS_LIB standard
J 0
(-1250 2900);
PAINT MONO (-1250 2900);
DISPLAY INVISIBLE (-1250 2900);
FORCEPROP 1 LAST OFFPAGE TRUE
J 0
(-925 2775);
DISPLAY 0.872340 (-925 2775);
PAINT GREEN (-925 2775);
DISPLAY INVISIBLE (-925 2775);
FORCEPROP 1 LAST COMMENT_BODY TRUE
J 0
(-1295 2805);
DISPLAY 0.872340 (-1295 2805);
PAINT GREEN (-1295 2805);
DISPLAY INVISIBLE (-1295 2805);
FORCEADD OFFPAGE..2
(-1250 3250);
FORCEPROP 2 LAST $XR0 44 
J 0
(-1061 3250);
DISPLAY 0.638298 (-1061 3250);
PAINT MONO (-1061 3250);
FORCEPROP 2 LAST PATH I382
J 0
(-1050 3300);
DISPLAY 1.021277 (-1050 3300);
DISPLAY INVISIBLE (-1050 3300);
FORCEPROP 1 LAST OFFPAGE TRUE
J 0
(-925 3125);
DISPLAY 0.872340 (-925 3125);
PAINT GREEN (-925 3125);
DISPLAY INVISIBLE (-925 3125);
FORCEPROP 1 LAST COMMENT_BODY TRUE
J 0
(-1295 3155);
DISPLAY 0.872340 (-1295 3155);
PAINT GREEN (-1295 3155);
DISPLAY INVISIBLE (-1295 3155);
FORCEPROP 2 LAST CDS_LIB standard
J 0
(-1250 3250);
PAINT MONO (-1250 3250);
DISPLAY INVISIBLE (-1250 3250);
FORCEADD OFFPAGE..2
(-1250 3400);
FORCEPROP 2 LAST $XR0 44 
J 0
(-1061 3400);
DISPLAY 0.638298 (-1061 3400);
PAINT MONO (-1061 3400);
FORCEPROP 2 LAST PATH I383
J 0
(-1050 3450);
DISPLAY 1.021277 (-1050 3450);
DISPLAY INVISIBLE (-1050 3450);
FORCEPROP 1 LAST OFFPAGE TRUE
J 0
(-925 3275);
DISPLAY 0.872340 (-925 3275);
PAINT GREEN (-925 3275);
DISPLAY INVISIBLE (-925 3275);
FORCEPROP 1 LAST COMMENT_BODY TRUE
J 0
(-1295 3305);
DISPLAY 0.872340 (-1295 3305);
PAINT GREEN (-1295 3305);
DISPLAY INVISIBLE (-1295 3305);
FORCEPROP 2 LAST CDS_LIB standard
J 0
(-1250 3400);
PAINT MONO (-1250 3400);
DISPLAY INVISIBLE (-1250 3400);
FORCEADD OFFPAGE..2
(-1250 3350);
FORCEPROP 2 LAST $XR0 44 
J 0
(-1061 3350);
DISPLAY 0.638298 (-1061 3350);
PAINT MONO (-1061 3350);
FORCEPROP 2 LAST PATH I384
J 0
(-1050 3400);
DISPLAY 1.021277 (-1050 3400);
DISPLAY INVISIBLE (-1050 3400);
FORCEPROP 2 LAST CDS_LIB standard
J 0
(-1250 3350);
PAINT MONO (-1250 3350);
DISPLAY INVISIBLE (-1250 3350);
FORCEPROP 1 LAST OFFPAGE TRUE
J 0
(-925 3225);
DISPLAY 0.872340 (-925 3225);
PAINT GREEN (-925 3225);
DISPLAY INVISIBLE (-925 3225);
FORCEPROP 1 LAST COMMENT_BODY TRUE
J 0
(-1295 3255);
DISPLAY 0.872340 (-1295 3255);
PAINT GREEN (-1295 3255);
DISPLAY INVISIBLE (-1295 3255);
FORCEADD OFFPAGE..2
(-1250 3200);
FORCEPROP 2 LAST $XR0 44 
J 0
(-1061 3200);
DISPLAY 0.638298 (-1061 3200);
PAINT MONO (-1061 3200);
FORCEPROP 2 LAST PATH I385
J 0
(-1050 3250);
DISPLAY 1.021277 (-1050 3250);
DISPLAY INVISIBLE (-1050 3250);
FORCEPROP 2 LAST CDS_LIB standard
J 0
(-1250 3200);
PAINT MONO (-1250 3200);
DISPLAY INVISIBLE (-1250 3200);
FORCEPROP 1 LAST OFFPAGE TRUE
J 0
(-925 3075);
DISPLAY 0.872340 (-925 3075);
PAINT GREEN (-925 3075);
DISPLAY INVISIBLE (-925 3075);
FORCEPROP 1 LAST COMMENT_BODY TRUE
J 0
(-1295 3105);
DISPLAY 0.872340 (-1295 3105);
PAINT GREEN (-1295 3105);
DISPLAY INVISIBLE (-1295 3105);
FORCEADD OFFPAGE..2
(-1250 3100);
FORCEPROP 2 LAST $XR0 44 
J 0
(-1061 3100);
DISPLAY 0.638298 (-1061 3100);
PAINT MONO (-1061 3100);
FORCEPROP 2 LAST PATH I386
J 0
(-1050 3150);
DISPLAY 1.021277 (-1050 3150);
DISPLAY INVISIBLE (-1050 3150);
FORCEPROP 1 LAST OFFPAGE TRUE
J 0
(-925 2975);
DISPLAY 0.872340 (-925 2975);
PAINT GREEN (-925 2975);
DISPLAY INVISIBLE (-925 2975);
FORCEPROP 1 LAST COMMENT_BODY TRUE
J 0
(-1295 3005);
DISPLAY 0.872340 (-1295 3005);
PAINT GREEN (-1295 3005);
DISPLAY INVISIBLE (-1295 3005);
FORCEPROP 2 LAST CDS_LIB standard
J 0
(-1250 3100);
PAINT MONO (-1250 3100);
DISPLAY INVISIBLE (-1250 3100);
FORCEADD OFFPAGE..2
(-1250 3050);
FORCEPROP 2 LAST $XR0 44 
J 0
(-1061 3050);
DISPLAY 0.638298 (-1061 3050);
PAINT MONO (-1061 3050);
FORCEPROP 2 LAST PATH I387
J 0
(-1050 3100);
DISPLAY 1.021277 (-1050 3100);
DISPLAY INVISIBLE (-1050 3100);
FORCEPROP 2 LAST CDS_LIB standard
J 0
(-1250 3050);
PAINT MONO (-1250 3050);
DISPLAY INVISIBLE (-1250 3050);
FORCEPROP 1 LAST OFFPAGE TRUE
J 0
(-925 2925);
DISPLAY 0.872340 (-925 2925);
PAINT GREEN (-925 2925);
DISPLAY INVISIBLE (-925 2925);
FORCEPROP 1 LAST COMMENT_BODY TRUE
J 0
(-1295 2955);
DISPLAY 0.872340 (-1295 2955);
PAINT GREEN (-1295 2955);
DISPLAY INVISIBLE (-1295 2955);
FORCEADD OFFPAGE..2
(-1250 2950);
FORCEPROP 2 LAST $XR0 44 
J 0
(-1061 2950);
DISPLAY 0.638298 (-1061 2950);
PAINT MONO (-1061 2950);
FORCEPROP 2 LAST PATH I388
J 0
(-1050 3000);
DISPLAY 1.021277 (-1050 3000);
DISPLAY INVISIBLE (-1050 3000);
FORCEPROP 2 LAST CDS_LIB standard
J 0
(-1250 2950);
PAINT MONO (-1250 2950);
DISPLAY INVISIBLE (-1250 2950);
FORCEPROP 1 LAST OFFPAGE TRUE
J 0
(-925 2825);
DISPLAY 0.872340 (-925 2825);
PAINT GREEN (-925 2825);
DISPLAY INVISIBLE (-925 2825);
FORCEPROP 1 LAST COMMENT_BODY TRUE
J 0
(-1295 2855);
DISPLAY 0.872340 (-1295 2855);
PAINT GREEN (-1295 2855);
DISPLAY INVISIBLE (-1295 2855);
FORCEADD OFFPAGE..1
(-4875 3300);
FORCEPROP 2 LAST $XR0 237 
J 0
(-5157 3300);
DISPLAY 0.638298 (-5157 3300);
PAINT MONO (-5157 3300);
FORCEPROP 1 LAST OFFPAGE TRUE
J 0
(-4550 3175);
DISPLAY 0.872340 (-4550 3175);
PAINT GREEN (-4550 3175);
DISPLAY INVISIBLE (-4550 3175);
FORCEPROP 1 LAST COMMENT_BODY TRUE
J 0
(-4750 3200);
DISPLAY 0.872340 (-4750 3200);
PAINT GREEN (-4750 3200);
DISPLAY INVISIBLE (-4750 3200);
FORCEPROP 2 LAST PATH I409
J 0
(-5150 3350);
DISPLAY 1.021277 (-5150 3350);
DISPLAY INVISIBLE (-5150 3350);
FORCEPROP 2 LAST CDS_LIB standard
J 0
(-4875 3300);
PAINT MONO (-4875 3300);
DISPLAY INVISIBLE (-4875 3300);
FORCEADD OFFPAGE..3
R 2
(-4875 3250);
FORCEPROP 2 LAST $XR0 237 
J 0
(-5185 3250);
DISPLAY 0.638298 (-5185 3250);
PAINT MONO (-5185 3250);
FORCEPROP 1 LAST COMMENT_BODY TRUE
J 2
(-4825 3150);
DISPLAY 0.872340 (-4825 3150);
PAINT GREEN (-4825 3150);
DISPLAY INVISIBLE (-4825 3150);
FORCEPROP 1 LAST OFFPAGE TRUE
J 2
(-5200 3125);
DISPLAY 0.872340 (-5200 3125);
DISPLAY INVISIBLE (-5200 3125);
FORCEPROP 2 LAST PATH I410
J 0
(-5200 3300);
DISPLAY 1.021277 (-5200 3300);
DISPLAY INVISIBLE (-5200 3300);
FORCEPROP 2 LAST CDS_LIB standard
J 0
(-4875 3250);
PAINT MONO (-4875 3250);
DISPLAY INVISIBLE (-4875 3250);
FORCEADD Q_CAP..1
(-7300 4975);
FORCEPROP 1 LAST PART_NUMBER CH6101ME900
J 0
(-7250 4850);
DISPLAY 0.510638 (-7250 4850);
DISPLAY INVISIBLE (-7250 4850);
FORCEPROP 1 LAST TOLERANCE 20%
J 0
(-7250 4950);
DISPLAY 0.510638 (-7250 4950);
FORCEPROP 1 LAST VALUE 10UF
J 0
(-7250 5050);
DISPLAY 0.510638 (-7250 5050);
FORCEPROP 1 LAST VOLTAGE 6.3V
J 0
(-7250 5000);
DISPLAY 0.510638 (-7250 5000);
FORCEPROP 1 LAST MATERIAL X6S
J 0
(-7250 4900);
DISPLAY 0.510638 (-7250 4900);
FORCEPROP 1 LAST PACK_TYPE C0603
J 0
(-7250 4800);
DISPLAY 0.510638 (-7250 4800);
FORCEPROP 1 LAST $LOCATION C1409
J 0
(-7250 5100);
DISPLAY 0.978723 (-7250 5100);
FORCEPROP 1 LASTPIN (-7300 5075) $PN 1
J 0
(-7290 5055);
DISPLAY 0.787234 (-7290 5055);
FORCEPROP 1 LASTPIN (-7300 4875) $PN 2
J 0
(-7290 4855);
DISPLAY 0.787234 (-7290 4855);
FORCEPROP 2 LAST CDS_LIB pure_quanta
J 0
(-7300 4975);
PAINT MONO (-7300 4975);
DISPLAY INVISIBLE (-7300 4975);
FORCEPROP 1 LAST PATH I419
J 0
(-7250 5125);
DISPLAY 0.978723 (-7250 5125);
PAINT WHITE (-7250 5125);
DISPLAY INVISIBLE (-7250 5125);
FORCEPROP 2 LAST CDS_LOCATION C1409
J 0
(-7250 5175);
DISPLAY 1.021277 (-7250 5175);
DISPLAY INVISIBLE (-7250 5175);
FORCEPROP 2 LAST $SEC 1
J 0
(-7250 5175);
DISPLAY 0.680851 (-7250 5175);
PAINT MONO (-7250 5175);
DISPLAY INVISIBLE (-7250 5175);
FORCEPROP 2 LAST CDS_SEC 1
J 0
(-7250 5175);
DISPLAY 1.021277 (-7250 5175);
DISPLAY INVISIBLE (-7250 5175);
FORCEADD UNIVERSAL_GND..1
(-7075 3650);
FORCEPROP 3 LASTPIN (-7075 3700) SIG_NAME GND\g
J 0
(-7065 3710);
DISPLAY 0.659574 (-7065 3710);
PAINT MONO (-7065 3710);
DISPLAY INVISIBLE (-7065 3710);
FORCEPROP 1 LAST HDL_POWER GND
J 1
(-7050 3575);
DISPLAY 0.872340 (-7050 3575);
PAINT GREEN (-7050 3575);
DISPLAY INVISIBLE (-7050 3575);
FORCEPROP 1 LAST PATH I432
J 0
(-7000 3650);
DISPLAY 0.872340 (-7000 3650);
PAINT AQUA (-7000 3650);
DISPLAY INVISIBLE (-7000 3650);
FORCEPROP 2 LAST CDS_LIB logical_power
J 0
(-7075 3650);
DISPLAY INVISIBLE (-7075 3650);
FORCEADD UNIVERSAL_GND..1
(-7075 2775);
FORCEPROP 3 LASTPIN (-7075 2825) SIG_NAME GND\g
J 0
(-7065 2835);
DISPLAY 0.659574 (-7065 2835);
PAINT MONO (-7065 2835);
DISPLAY INVISIBLE (-7065 2835);
FORCEPROP 1 LAST HDL_POWER GND
J 1
(-7050 2700);
DISPLAY 0.872340 (-7050 2700);
PAINT GREEN (-7050 2700);
DISPLAY INVISIBLE (-7050 2700);
FORCEPROP 1 LAST PATH I433
J 0
(-7000 2775);
DISPLAY 0.872340 (-7000 2775);
PAINT AQUA (-7000 2775);
DISPLAY INVISIBLE (-7000 2775);
FORCEPROP 2 LAST CDS_LIB logical_power
J 0
(-7075 2775);
DISPLAY INVISIBLE (-7075 2775);
FORCEADD UNIVERSAL_GND..1
(-6575 2325);
FORCEPROP 3 LASTPIN (-6575 2375) SIG_NAME GND\g
J 0
(-6565 2385);
DISPLAY 0.659574 (-6565 2385);
PAINT MONO (-6565 2385);
DISPLAY INVISIBLE (-6565 2385);
FORCEPROP 2 LAST CDS_LIB logical_power
J 0
(-6575 2325);
DISPLAY INVISIBLE (-6575 2325);
FORCEPROP 1 LAST PATH I434
J 0
(-6500 2325);
DISPLAY 0.872340 (-6500 2325);
PAINT AQUA (-6500 2325);
DISPLAY INVISIBLE (-6500 2325);
FORCEPROP 1 LAST HDL_POWER GND
J 1
(-6550 2250);
DISPLAY 0.872340 (-6550 2250);
PAINT GREEN (-6550 2250);
DISPLAY INVISIBLE (-6550 2250);
FORCEADD UNIVERSAL_GND..1
(-7300 4700);
FORCEPROP 3 LASTPIN (-7300 4750) SIG_NAME GND\g
J 0
(-7290 4760);
DISPLAY 0.659574 (-7290 4760);
PAINT MONO (-7290 4760);
DISPLAY INVISIBLE (-7290 4760);
FORCEPROP 1 LAST HDL_POWER GND
J 1
(-7275 4625);
DISPLAY 0.872340 (-7275 4625);
PAINT GREEN (-7275 4625);
DISPLAY INVISIBLE (-7275 4625);
FORCEPROP 1 LAST PATH I435
J 0
(-7225 4700);
DISPLAY 0.872340 (-7225 4700);
PAINT AQUA (-7225 4700);
DISPLAY INVISIBLE (-7225 4700);
FORCEPROP 2 LAST CDS_LIB logical_power
J 0
(-7300 4700);
DISPLAY INVISIBLE (-7300 4700);
FORCEADD UNIVERSAL_GND..1
(-9225 -200);
FORCEPROP 3 LASTPIN (-9225 -150) SIG_NAME GND\g
J 0
(-9215 -140);
DISPLAY 0.659574 (-9215 -140);
PAINT MONO (-9215 -140);
DISPLAY INVISIBLE (-9215 -140);
FORCEPROP 1 LAST HDL_POWER GND
J 1
(-9200 -275);
DISPLAY 0.872340 (-9200 -275);
PAINT GREEN (-9200 -275);
DISPLAY INVISIBLE (-9200 -275);
FORCEPROP 1 LAST PATH I436
J 0
(-9150 -200);
DISPLAY 0.872340 (-9150 -200);
PAINT AQUA (-9150 -200);
DISPLAY INVISIBLE (-9150 -200);
FORCEPROP 2 LAST CDS_LIB logical_power
J 0
(-9225 -200);
DISPLAY INVISIBLE (-9225 -200);
FORCEADD UNIVERSAL_GND..1
(-9225 1225);
FORCEPROP 3 LASTPIN (-9225 1275) SIG_NAME GND\g
J 0
(-9215 1285);
DISPLAY 0.659574 (-9215 1285);
PAINT MONO (-9215 1285);
DISPLAY INVISIBLE (-9215 1285);
FORCEPROP 1 LAST HDL_POWER GND
J 1
(-9200 1150);
DISPLAY 0.872340 (-9200 1150);
PAINT GREEN (-9200 1150);
DISPLAY INVISIBLE (-9200 1150);
FORCEPROP 1 LAST PATH I437
J 0
(-9150 1225);
DISPLAY 0.872340 (-9150 1225);
PAINT AQUA (-9150 1225);
DISPLAY INVISIBLE (-9150 1225);
FORCEPROP 2 LAST CDS_LIB logical_power
J 0
(-9225 1225);
DISPLAY INVISIBLE (-9225 1225);
FORCEADD UNIVERSAL_GND..1
(-8825 1225);
FORCEPROP 3 LASTPIN (-8825 1275) SIG_NAME GND\g
J 0
(-8815 1285);
DISPLAY 0.659574 (-8815 1285);
PAINT MONO (-8815 1285);
DISPLAY INVISIBLE (-8815 1285);
FORCEPROP 1 LAST HDL_POWER GND
J 1
(-8800 1150);
DISPLAY 0.872340 (-8800 1150);
PAINT GREEN (-8800 1150);
DISPLAY INVISIBLE (-8800 1150);
FORCEPROP 1 LAST PATH I438
J 0
(-8750 1225);
DISPLAY 0.872340 (-8750 1225);
PAINT AQUA (-8750 1225);
DISPLAY INVISIBLE (-8750 1225);
FORCEPROP 2 LAST CDS_LIB logical_power
J 0
(-8825 1225);
DISPLAY INVISIBLE (-8825 1225);
FORCEADD UNIVERSAL_GND..1
(-2175 375);
FORCEPROP 3 LASTPIN (-2175 425) SIG_NAME GND\g
J 0
(-2165 435);
DISPLAY 0.659574 (-2165 435);
PAINT MONO (-2165 435);
DISPLAY INVISIBLE (-2165 435);
FORCEPROP 1 LAST HDL_POWER GND
J 1
(-2150 300);
DISPLAY 0.872340 (-2150 300);
PAINT GREEN (-2150 300);
DISPLAY INVISIBLE (-2150 300);
FORCEPROP 1 LAST PATH I439
J 0
(-2100 375);
DISPLAY 0.872340 (-2100 375);
PAINT AQUA (-2100 375);
DISPLAY INVISIBLE (-2100 375);
FORCEPROP 2 LAST CDS_LIB logical_power
J 0
(-2175 375);
DISPLAY INVISIBLE (-2175 375);
FORCEADD Q_RES..1
(-5300 2100);
FORCEPROP 1 LAST PART_NUMBER CS00002JB13
J 0
(-5375 2175);
DISPLAY 0.319149 (-5375 2175);
DISPLAY INVISIBLE (-5375 2175);
FORCEPROP 1 LAST VALUE 0
J 2
(-5100 2100);
DISPLAY 0.510638 (-5100 2100);
FORCEPROP 1 LAST TOLERANCE 5%
J 0
(-5050 2100);
DISPLAY 0.510638 (-5050 2100);
FORCEPROP 1 LAST MATERIAL CHIP
J 0
(-4975 2100);
DISPLAY 0.510638 (-4975 2100);
FORCEPROP 1 LAST $LOCATION R4534
J 0
(-5525 2100);
DISPLAY 0.510638 (-5525 2100);
FORCEPROP 1 LASTPIN (-5400 2100) $PN 1
J 0
(-5388 2112);
DISPLAY 0.787234 (-5388 2112);
PAINT MONO (-5388 2112);
FORCEPROP 1 LASTPIN (-5200 2100) $PN 2
J 0
(-5238 2112);
DISPLAY 0.787234 (-5238 2112);
PAINT MONO (-5238 2112);
FORCEPROP 2 LAST CDS_LIB pure_quanta
J 0
(-5300 2100);
DISPLAY INVISIBLE (-5300 2100);
FORCEPROP 1 LAST PACK_TYPE 0402LF
J 0
(-5375 2200);
DISPLAY 0.319149 (-5375 2200);
DISPLAY INVISIBLE (-5375 2200);
FORCEPROP 1 LAST WATTAGE 1/16W
J 2
(-5175 2200);
DISPLAY 0.319149 (-5175 2200);
DISPLAY INVISIBLE (-5175 2200);
FORCEPROP 1 LAST PATH I487
J 0
(-5350 2250);
DISPLAY 0.978723 (-5350 2250);
PAINT WHITE (-5350 2250);
DISPLAY INVISIBLE (-5350 2250);
FORCEPROP 0 LAST CDS_LOCATION R4534
J 0
(-5525 2150);
DISPLAY 1.021277 (-5525 2150);
DISPLAY INVISIBLE (-5525 2150);
FORCEPROP 0 LAST $SEC 1
J 0
(-5525 2150);
DISPLAY 0.680851 (-5525 2150);
PAINT MONO (-5525 2150);
DISPLAY INVISIBLE (-5525 2150);
FORCEPROP 0 LAST CDS_SEC 1
J 0
(-5525 2150);
DISPLAY 1.021277 (-5525 2150);
DISPLAY INVISIBLE (-5525 2150);
FORCEADD OFFPAGE..1
(-8175 2100);
FORCEPROP 2 LAST $XR0 215 
J 0
(-8427 2100);
DISPLAY 0.638298 (-8427 2100);
PAINT MONO (-8427 2100);
FORCEPROP 2 LAST CDS_LIB standard
J 0
(-8175 2100);
PAINT MONO (-8175 2100);
DISPLAY INVISIBLE (-8175 2100);
FORCEPROP 2 LAST PATH I488
J 0
(-8475 2150);
DISPLAY 1.021277 (-8475 2150);
DISPLAY INVISIBLE (-8475 2150);
FORCEPROP 1 LAST OFFPAGE TRUE
J 0
(-7850 1975);
DISPLAY 0.872340 (-7850 1975);
PAINT GREEN (-7850 1975);
DISPLAY INVISIBLE (-7850 1975);
FORCEPROP 1 LAST COMMENT_BODY TRUE
J 0
(-8050 2000);
DISPLAY 0.872340 (-8050 2000);
PAINT GREEN (-8050 2000);
DISPLAY INVISIBLE (-8050 2000);
FORCEADD OFFPAGE..2
(-1250 1750);
FORCEPROP 2 LAST $XR0 207 
J 0
(-1061 1750);
DISPLAY 0.638298 (-1061 1750);
PAINT MONO (-1061 1750);
FORCEPROP 2 LAST CDS_LIB standard
J 0
(-1250 1750);
DISPLAY INVISIBLE (-1250 1750);
FORCEPROP 2 LAST PATH I502
J 0
(-1075 1825);
DISPLAY 1.021277 (-1075 1825);
DISPLAY INVISIBLE (-1075 1825);
FORCEPROP 1 LAST OFFPAGE TRUE
J 0
(-925 1625);
DISPLAY 0.872340 (-925 1625);
PAINT GREEN (-925 1625);
DISPLAY INVISIBLE (-925 1625);
FORCEPROP 1 LAST COMMENT_BODY TRUE
J 0
(-1295 1655);
DISPLAY 0.872340 (-1295 1655);
PAINT GREEN (-1295 1655);
DISPLAY INVISIBLE (-1295 1655);
FORCEADD OFFPAGE..2
(-1250 1700);
FORCEPROP 2 LAST $XR0 207 
J 0
(-1061 1700);
DISPLAY 0.638298 (-1061 1700);
PAINT MONO (-1061 1700);
FORCEPROP 2 LAST CDS_LIB standard
J 0
(-1250 1700);
DISPLAY INVISIBLE (-1250 1700);
FORCEPROP 2 LAST PATH I503
J 0
(-1075 1775);
DISPLAY 1.021277 (-1075 1775);
DISPLAY INVISIBLE (-1075 1775);
FORCEPROP 1 LAST COMMENT_BODY TRUE
J 0
(-1295 1605);
DISPLAY 0.872340 (-1295 1605);
PAINT GREEN (-1295 1605);
DISPLAY INVISIBLE (-1295 1605);
FORCEPROP 1 LAST OFFPAGE TRUE
J 0
(-925 1575);
DISPLAY 0.872340 (-925 1575);
PAINT GREEN (-925 1575);
DISPLAY INVISIBLE (-925 1575);
FORCEADD OFFPAGE..2
(-1250 1850);
FORCEPROP 2 LAST $XR0 207 
J 0
(-1061 1850);
DISPLAY 0.638298 (-1061 1850);
PAINT MONO (-1061 1850);
FORCEPROP 2 LAST CDS_LIB standard
J 0
(-1250 1850);
DISPLAY INVISIBLE (-1250 1850);
FORCEPROP 2 LAST PATH I504
J 0
(-1075 1925);
DISPLAY 1.021277 (-1075 1925);
DISPLAY INVISIBLE (-1075 1925);
FORCEPROP 1 LAST OFFPAGE TRUE
J 0
(-925 1725);
DISPLAY 0.872340 (-925 1725);
PAINT GREEN (-925 1725);
DISPLAY INVISIBLE (-925 1725);
FORCEPROP 1 LAST COMMENT_BODY TRUE
J 0
(-1295 1755);
DISPLAY 0.872340 (-1295 1755);
PAINT GREEN (-1295 1755);
DISPLAY INVISIBLE (-1295 1755);
FORCEADD OFFPAGE..2
(-1250 1900);
FORCEPROP 2 LAST $XR0 207 
J 0
(-1061 1900);
DISPLAY 0.638298 (-1061 1900);
PAINT MONO (-1061 1900);
FORCEPROP 2 LAST CDS_LIB standard
J 0
(-1250 1900);
DISPLAY INVISIBLE (-1250 1900);
FORCEPROP 2 LAST PATH I505
J 0
(-1075 1975);
DISPLAY 1.021277 (-1075 1975);
DISPLAY INVISIBLE (-1075 1975);
FORCEPROP 1 LAST COMMENT_BODY TRUE
J 0
(-1295 1805);
DISPLAY 0.872340 (-1295 1805);
PAINT GREEN (-1295 1805);
DISPLAY INVISIBLE (-1295 1805);
FORCEPROP 1 LAST OFFPAGE TRUE
J 0
(-925 1775);
DISPLAY 0.872340 (-925 1775);
PAINT GREEN (-925 1775);
DISPLAY INVISIBLE (-925 1775);
FORCEADD OFFPAGE..2
(-1250 1550);
FORCEPROP 2 LAST $XR0 207 
J 0
(-1061 1550);
DISPLAY 0.638298 (-1061 1550);
PAINT MONO (-1061 1550);
FORCEPROP 2 LAST CDS_LIB standard
J 0
(-1250 1550);
DISPLAY INVISIBLE (-1250 1550);
FORCEPROP 2 LAST PATH I506
J 0
(-1075 1625);
DISPLAY 1.021277 (-1075 1625);
DISPLAY INVISIBLE (-1075 1625);
FORCEPROP 1 LAST COMMENT_BODY TRUE
J 0
(-1295 1455);
DISPLAY 0.872340 (-1295 1455);
PAINT GREEN (-1295 1455);
DISPLAY INVISIBLE (-1295 1455);
FORCEPROP 1 LAST OFFPAGE TRUE
J 0
(-925 1425);
DISPLAY 0.872340 (-925 1425);
PAINT GREEN (-925 1425);
DISPLAY INVISIBLE (-925 1425);
FORCEADD OFFPAGE..2
(-1250 1600);
FORCEPROP 2 LAST $XR0 207 
J 0
(-1061 1600);
DISPLAY 0.638298 (-1061 1600);
PAINT MONO (-1061 1600);
FORCEPROP 2 LAST CDS_LIB standard
J 0
(-1250 1600);
DISPLAY INVISIBLE (-1250 1600);
FORCEPROP 2 LAST PATH I507
J 0
(-1075 1675);
DISPLAY 1.021277 (-1075 1675);
DISPLAY INVISIBLE (-1075 1675);
FORCEPROP 1 LAST OFFPAGE TRUE
J 0
(-925 1475);
DISPLAY 0.872340 (-925 1475);
PAINT GREEN (-925 1475);
DISPLAY INVISIBLE (-925 1475);
FORCEPROP 1 LAST COMMENT_BODY TRUE
J 0
(-1295 1505);
DISPLAY 0.872340 (-1295 1505);
PAINT GREEN (-1295 1505);
DISPLAY INVISIBLE (-1295 1505);
FORCEADD OFFPAGE..2
(-1250 1450);
FORCEPROP 2 LAST $XR0 207 
J 0
(-1061 1450);
DISPLAY 0.638298 (-1061 1450);
PAINT MONO (-1061 1450);
FORCEPROP 2 LAST CDS_LIB standard
J 0
(-1250 1450);
DISPLAY INVISIBLE (-1250 1450);
FORCEPROP 2 LAST PATH I508
J 0
(-1075 1525);
DISPLAY 1.021277 (-1075 1525);
DISPLAY INVISIBLE (-1075 1525);
FORCEPROP 1 LAST COMMENT_BODY TRUE
J 0
(-1295 1355);
DISPLAY 0.872340 (-1295 1355);
PAINT GREEN (-1295 1355);
DISPLAY INVISIBLE (-1295 1355);
FORCEPROP 1 LAST OFFPAGE TRUE
J 0
(-925 1325);
DISPLAY 0.872340 (-925 1325);
PAINT GREEN (-925 1325);
DISPLAY INVISIBLE (-925 1325);
FORCEADD OFFPAGE..2
(-1250 1400);
FORCEPROP 2 LAST $XR0 207 
J 0
(-1061 1400);
DISPLAY 0.638298 (-1061 1400);
PAINT MONO (-1061 1400);
FORCEPROP 2 LAST CDS_LIB standard
J 0
(-1250 1400);
DISPLAY INVISIBLE (-1250 1400);
FORCEPROP 2 LAST PATH I509
J 0
(-1075 1475);
DISPLAY 1.021277 (-1075 1475);
DISPLAY INVISIBLE (-1075 1475);
FORCEPROP 1 LAST OFFPAGE TRUE
J 0
(-925 1275);
DISPLAY 0.872340 (-925 1275);
PAINT GREEN (-925 1275);
DISPLAY INVISIBLE (-925 1275);
FORCEPROP 1 LAST COMMENT_BODY TRUE
J 0
(-1295 1305);
DISPLAY 0.872340 (-1295 1305);
PAINT GREEN (-1295 1305);
DISPLAY INVISIBLE (-1295 1305);
FORCEADD OFFPAGE..2
(-1250 2800);
FORCEPROP 2 LAST $XR0 211 
J 0
(-1061 2800);
DISPLAY 0.638298 (-1061 2800);
PAINT MONO (-1061 2800);
FORCEPROP 2 LAST PATH I519
J 0
(-1050 2850);
DISPLAY 1.021277 (-1050 2850);
DISPLAY INVISIBLE (-1050 2850);
FORCEPROP 2 LAST CDS_LIB standard
J 0
(-1250 2800);
PAINT MONO (-1250 2800);
DISPLAY INVISIBLE (-1250 2800);
FORCEPROP 1 LAST OFFPAGE TRUE
J 0
(-925 2675);
DISPLAY 0.872340 (-925 2675);
PAINT GREEN (-925 2675);
DISPLAY INVISIBLE (-925 2675);
FORCEPROP 1 LAST COMMENT_BODY TRUE
J 0
(-1295 2705);
DISPLAY 0.872340 (-1295 2705);
PAINT GREEN (-1295 2705);
DISPLAY INVISIBLE (-1295 2705);
FORCEADD OFFPAGE..2
(-1250 2750);
FORCEPROP 2 LAST $XR0 211 
J 0
(-1061 2750);
DISPLAY 0.638298 (-1061 2750);
PAINT MONO (-1061 2750);
FORCEPROP 2 LAST PATH I520
J 0
(-1050 2800);
DISPLAY 1.021277 (-1050 2800);
DISPLAY INVISIBLE (-1050 2800);
FORCEPROP 2 LAST CDS_LIB standard
J 0
(-1250 2750);
PAINT MONO (-1250 2750);
DISPLAY INVISIBLE (-1250 2750);
FORCEPROP 1 LAST OFFPAGE TRUE
J 0
(-925 2625);
DISPLAY 0.872340 (-925 2625);
PAINT GREEN (-925 2625);
DISPLAY INVISIBLE (-925 2625);
FORCEPROP 1 LAST COMMENT_BODY TRUE
J 0
(-1295 2655);
DISPLAY 0.872340 (-1295 2655);
PAINT GREEN (-1295 2655);
DISPLAY INVISIBLE (-1295 2655);
FORCEADD OFFPAGE..2
(-1250 2200);
FORCEPROP 2 LAST $XR0 209 
J 0
(-1061 2200);
DISPLAY 0.638298 (-1061 2200);
PAINT MONO (-1061 2200);
FORCEPROP 2 LAST PATH I523
J 0
(-1050 2250);
DISPLAY 1.021277 (-1050 2250);
DISPLAY INVISIBLE (-1050 2250);
FORCEPROP 2 LAST CDS_LIB standard
J 0
(-1250 2200);
PAINT MONO (-1250 2200);
DISPLAY INVISIBLE (-1250 2200);
FORCEPROP 1 LAST COMMENT_BODY TRUE
J 0
(-1295 2105);
DISPLAY 0.872340 (-1295 2105);
PAINT GREEN (-1295 2105);
DISPLAY INVISIBLE (-1295 2105);
FORCEPROP 1 LAST OFFPAGE TRUE
J 0
(-925 2075);
DISPLAY 0.872340 (-925 2075);
PAINT GREEN (-925 2075);
DISPLAY INVISIBLE (-925 2075);
FORCEADD OFFPAGE..2
(-1250 2350);
FORCEPROP 2 LAST $XR0 209 
J 0
(-1061 2350);
DISPLAY 0.638298 (-1061 2350);
PAINT MONO (-1061 2350);
FORCEPROP 2 LAST PATH I524
J 0
(-1050 2400);
DISPLAY 1.021277 (-1050 2400);
DISPLAY INVISIBLE (-1050 2400);
FORCEPROP 2 LAST CDS_LIB standard
J 0
(-1250 2350);
PAINT MONO (-1250 2350);
DISPLAY INVISIBLE (-1250 2350);
FORCEPROP 1 LAST COMMENT_BODY TRUE
J 0
(-1295 2255);
DISPLAY 0.872340 (-1295 2255);
PAINT GREEN (-1295 2255);
DISPLAY INVISIBLE (-1295 2255);
FORCEPROP 1 LAST OFFPAGE TRUE
J 0
(-925 2225);
DISPLAY 0.872340 (-925 2225);
PAINT GREEN (-925 2225);
DISPLAY INVISIBLE (-925 2225);
FORCEADD OFFPAGE..2
(-1250 2300);
FORCEPROP 2 LAST $XR0 209 
J 0
(-1061 2300);
DISPLAY 0.638298 (-1061 2300);
PAINT MONO (-1061 2300);
FORCEPROP 2 LAST PATH I525
J 0
(-1050 2350);
DISPLAY 1.021277 (-1050 2350);
DISPLAY INVISIBLE (-1050 2350);
FORCEPROP 1 LAST COMMENT_BODY TRUE
J 0
(-1295 2205);
DISPLAY 0.872340 (-1295 2205);
PAINT GREEN (-1295 2205);
DISPLAY INVISIBLE (-1295 2205);
FORCEPROP 1 LAST OFFPAGE TRUE
J 0
(-925 2175);
DISPLAY 0.872340 (-925 2175);
PAINT GREEN (-925 2175);
DISPLAY INVISIBLE (-925 2175);
FORCEPROP 2 LAST CDS_LIB standard
J 0
(-1250 2300);
PAINT MONO (-1250 2300);
DISPLAY INVISIBLE (-1250 2300);
FORCEADD OFFPAGE..2
(-1250 2150);
FORCEPROP 2 LAST $XR0 209 
J 0
(-1061 2150);
DISPLAY 0.638298 (-1061 2150);
PAINT MONO (-1061 2150);
FORCEPROP 2 LAST PATH I528
J 0
(-1050 2200);
DISPLAY 1.021277 (-1050 2200);
DISPLAY INVISIBLE (-1050 2200);
FORCEPROP 1 LAST COMMENT_BODY TRUE
J 0
(-1295 2055);
DISPLAY 0.872340 (-1295 2055);
PAINT GREEN (-1295 2055);
DISPLAY INVISIBLE (-1295 2055);
FORCEPROP 1 LAST OFFPAGE TRUE
J 0
(-925 2025);
DISPLAY 0.872340 (-925 2025);
PAINT GREEN (-925 2025);
DISPLAY INVISIBLE (-925 2025);
FORCEPROP 2 LAST CDS_LIB standard
J 0
(-1250 2150);
PAINT MONO (-1250 2150);
DISPLAY INVISIBLE (-1250 2150);
FORCEADD OFFPAGE..2
(-1250 2500);
FORCEPROP 2 LAST $XR0 209 
J 0
(-1061 2500);
DISPLAY 0.638298 (-1061 2500);
PAINT MONO (-1061 2500);
FORCEPROP 1 LAST OFFPAGE TRUE
J 0
(-925 2375);
DISPLAY 0.872340 (-925 2375);
PAINT GREEN (-925 2375);
DISPLAY INVISIBLE (-925 2375);
FORCEPROP 1 LAST COMMENT_BODY TRUE
J 0
(-1295 2405);
DISPLAY 0.872340 (-1295 2405);
PAINT GREEN (-1295 2405);
DISPLAY INVISIBLE (-1295 2405);
FORCEPROP 2 LAST CDS_LIB standard
J 0
(-1250 2500);
PAINT MONO (-1250 2500);
DISPLAY INVISIBLE (-1250 2500);
FORCEPROP 2 LAST PATH I529
J 0
(-1050 2550);
DISPLAY 1.021277 (-1050 2550);
DISPLAY INVISIBLE (-1050 2550);
FORCEADD OFFPAGE..2
(-1250 2450);
FORCEPROP 2 LAST $XR0 209 
J 0
(-1061 2450);
DISPLAY 0.638298 (-1061 2450);
PAINT MONO (-1061 2450);
FORCEPROP 2 LAST CDS_LIB standard
J 0
(-1250 2450);
PAINT MONO (-1250 2450);
DISPLAY INVISIBLE (-1250 2450);
FORCEPROP 1 LAST OFFPAGE TRUE
J 0
(-925 2325);
DISPLAY 0.872340 (-925 2325);
PAINT GREEN (-925 2325);
DISPLAY INVISIBLE (-925 2325);
FORCEPROP 1 LAST COMMENT_BODY TRUE
J 0
(-1295 2355);
DISPLAY 0.872340 (-1295 2355);
PAINT GREEN (-1295 2355);
DISPLAY INVISIBLE (-1295 2355);
FORCEPROP 2 LAST PATH I530
J 0
(-1050 2500);
DISPLAY 1.021277 (-1050 2500);
DISPLAY INVISIBLE (-1050 2500);
FORCEADD OFFPAGE..2
(-1250 2600);
FORCEPROP 2 LAST $XR0 209 
J 0
(-1061 2600);
DISPLAY 0.638298 (-1061 2600);
PAINT MONO (-1061 2600);
FORCEPROP 2 LAST PATH I531
J 0
(-1050 2650);
DISPLAY 1.021277 (-1050 2650);
DISPLAY INVISIBLE (-1050 2650);
FORCEPROP 2 LAST CDS_LIB standard
J 0
(-1250 2600);
PAINT MONO (-1250 2600);
DISPLAY INVISIBLE (-1250 2600);
FORCEPROP 1 LAST OFFPAGE TRUE
J 0
(-925 2475);
DISPLAY 0.872340 (-925 2475);
PAINT GREEN (-925 2475);
DISPLAY INVISIBLE (-925 2475);
FORCEPROP 1 LAST COMMENT_BODY TRUE
J 0
(-1295 2505);
DISPLAY 0.872340 (-1295 2505);
PAINT GREEN (-1295 2505);
DISPLAY INVISIBLE (-1295 2505);
FORCEADD OFFPAGE..2
(-1250 2650);
FORCEPROP 2 LAST $XR0 209 
J 0
(-1061 2650);
DISPLAY 0.638298 (-1061 2650);
PAINT MONO (-1061 2650);
FORCEPROP 2 LAST PATH I532
J 0
(-1050 2700);
DISPLAY 1.021277 (-1050 2700);
DISPLAY INVISIBLE (-1050 2700);
FORCEPROP 1 LAST OFFPAGE TRUE
J 0
(-925 2525);
DISPLAY 0.872340 (-925 2525);
PAINT GREEN (-925 2525);
DISPLAY INVISIBLE (-925 2525);
FORCEPROP 1 LAST COMMENT_BODY TRUE
J 0
(-1295 2555);
DISPLAY 0.872340 (-1295 2555);
PAINT GREEN (-1295 2555);
DISPLAY INVISIBLE (-1295 2555);
FORCEPROP 2 LAST CDS_LIB standard
J 0
(-1250 2650);
PAINT MONO (-1250 2650);
DISPLAY INVISIBLE (-1250 2650);
FORCEADD Q_RES..1
(-5300 2050);
FORCEPROP 1 LAST PART_NUMBER CS00002JB13
J 0
(-5375 2125);
DISPLAY 0.319149 (-5375 2125);
DISPLAY INVISIBLE (-5375 2125);
FORCEPROP 1 LAST VALUE 0
J 2
(-5100 2050);
DISPLAY 0.510638 (-5100 2050);
FORCEPROP 1 LAST MATERIAL CHIP
J 0
(-4975 2050);
DISPLAY 0.510638 (-4975 2050);
FORCEPROP 1 LAST TOLERANCE 5%
J 0
(-5050 2050);
DISPLAY 0.510638 (-5050 2050);
FORCEPROP 1 LAST LOCATION R1543
J 0
(-5500 2050);
DISPLAY 0.638298 (-5500 2050);
FORCEPROP 1 LASTPIN (-5400 2050) $PN 1
J 0
(-5388 2062);
DISPLAY 0.787234 (-5388 2062);
PAINT MONO (-5388 2062);
FORCEPROP 1 LASTPIN (-5200 2050) $PN 2
J 0
(-5238 2062);
DISPLAY 0.787234 (-5238 2062);
PAINT MONO (-5238 2062);
FORCEPROP 2 LAST CDS_LIB pure_quanta
J 0
(-5300 2050);
DISPLAY INVISIBLE (-5300 2050);
FORCEPROP 1 LAST PATH I534
J 0
(-5350 2200);
DISPLAY 0.978723 (-5350 2200);
PAINT WHITE (-5350 2200);
DISPLAY INVISIBLE (-5350 2200);
FORCEPROP 1 LAST WATTAGE 1/16W
J 2
(-5175 2150);
DISPLAY 0.319149 (-5175 2150);
DISPLAY INVISIBLE (-5175 2150);
FORCEPROP 1 LAST PACK_TYPE 0402LF
J 0
(-5375 2150);
DISPLAY 0.319149 (-5375 2150);
DISPLAY INVISIBLE (-5375 2150);
FORCEPROP 0 LAST $SEC 1
J 0
(-5500 2100);
DISPLAY 0.680851 (-5500 2100);
PAINT MONO (-5500 2100);
DISPLAY INVISIBLE (-5500 2100);
FORCEPROP 0 LAST CDS_SEC 1
J 0
(-5500 2100);
DISPLAY 1.021277 (-5500 2100);
DISPLAY INVISIBLE (-5500 2100);
FORCEADD Q_RES..1
(-5300 2000);
FORCEPROP 1 LAST PART_NUMBER CS00002JB13
J 0
(-5375 2075);
DISPLAY 0.319149 (-5375 2075);
DISPLAY INVISIBLE (-5375 2075);
FORCEPROP 1 LAST VALUE 0
J 2
(-5100 2000);
DISPLAY 0.510638 (-5100 2000);
FORCEPROP 1 LAST TOLERANCE 5%
J 0
(-5050 2000);
DISPLAY 0.510638 (-5050 2000);
FORCEPROP 1 LAST MATERIAL CHIP
J 0
(-4975 2000);
DISPLAY 0.510638 (-4975 2000);
FORCEPROP 1 LAST LOCATION R2562
J 0
(-5500 2000);
DISPLAY 0.638298 (-5500 2000);
FORCEPROP 1 LASTPIN (-5400 2000) $PN 1
J 0
(-5388 2012);
DISPLAY 0.787234 (-5388 2012);
PAINT MONO (-5388 2012);
FORCEPROP 1 LASTPIN (-5200 2000) $PN 2
J 0
(-5238 2012);
DISPLAY 0.787234 (-5238 2012);
PAINT MONO (-5238 2012);
FORCEPROP 2 LAST CDS_LIB pure_quanta
J 0
(-5300 2000);
DISPLAY INVISIBLE (-5300 2000);
FORCEPROP 1 LAST PATH I535
J 0
(-5350 2150);
DISPLAY 0.978723 (-5350 2150);
PAINT WHITE (-5350 2150);
DISPLAY INVISIBLE (-5350 2150);
FORCEPROP 1 LAST PACK_TYPE 0402LF
J 0
(-5375 2100);
DISPLAY 0.319149 (-5375 2100);
DISPLAY INVISIBLE (-5375 2100);
FORCEPROP 1 LAST WATTAGE 1/16W
J 2
(-5175 2100);
DISPLAY 0.319149 (-5175 2100);
DISPLAY INVISIBLE (-5175 2100);
FORCEPROP 0 LAST $SEC 1
J 0
(-5500 2050);
DISPLAY 0.680851 (-5500 2050);
PAINT MONO (-5500 2050);
DISPLAY INVISIBLE (-5500 2050);
FORCEPROP 0 LAST CDS_SEC 1
J 0
(-5500 2050);
DISPLAY 1.021277 (-5500 2050);
DISPLAY INVISIBLE (-5500 2050);
FORCEADD Q_RES..1
(-5300 1950);
FORCEPROP 1 LAST PART_NUMBER CS00002JB13
J 0
(-5375 2025);
DISPLAY 0.319149 (-5375 2025);
DISPLAY INVISIBLE (-5375 2025);
FORCEPROP 1 LAST VALUE 0
J 2
(-5100 1950);
DISPLAY 0.510638 (-5100 1950);
FORCEPROP 1 LAST TOLERANCE 5%
J 0
(-5050 1950);
DISPLAY 0.510638 (-5050 1950);
FORCEPROP 1 LAST MATERIAL CHIP
J 0
(-4975 1950);
DISPLAY 0.510638 (-4975 1950);
FORCEPROP 1 LAST LOCATION R3636
J 0
(-5500 1950);
DISPLAY 0.638298 (-5500 1950);
FORCEPROP 1 LASTPIN (-5400 1950) $PN 1
J 0
(-5388 1962);
DISPLAY 0.787234 (-5388 1962);
PAINT MONO (-5388 1962);
FORCEPROP 1 LASTPIN (-5200 1950) $PN 2
J 0
(-5238 1962);
DISPLAY 0.787234 (-5238 1962);
PAINT MONO (-5238 1962);
FORCEPROP 2 LAST CDS_LIB pure_quanta
J 0
(-5300 1950);
DISPLAY INVISIBLE (-5300 1950);
FORCEPROP 1 LAST PATH I536
J 0
(-5350 2100);
DISPLAY 0.978723 (-5350 2100);
PAINT WHITE (-5350 2100);
DISPLAY INVISIBLE (-5350 2100);
FORCEPROP 1 LAST PACK_TYPE 0402LF
J 0
(-5375 2050);
DISPLAY 0.319149 (-5375 2050);
DISPLAY INVISIBLE (-5375 2050);
FORCEPROP 1 LAST WATTAGE 1/16W
J 2
(-5175 2050);
DISPLAY 0.319149 (-5175 2050);
DISPLAY INVISIBLE (-5175 2050);
FORCEPROP 0 LAST $SEC 1
J 0
(-5500 2000);
DISPLAY 0.680851 (-5500 2000);
PAINT MONO (-5500 2000);
DISPLAY INVISIBLE (-5500 2000);
FORCEPROP 0 LAST CDS_SEC 1
J 0
(-5500 2000);
DISPLAY 1.021277 (-5500 2000);
DISPLAY INVISIBLE (-5500 2000);
FORCEADD Q_RES..1
(-5300 1900);
FORCEPROP 1 LAST PART_NUMBER CS00002JB13
J 0
(-5375 1975);
DISPLAY 0.319149 (-5375 1975);
DISPLAY INVISIBLE (-5375 1975);
FORCEPROP 1 LAST VALUE 0
J 2
(-5100 1900);
DISPLAY 0.510638 (-5100 1900);
FORCEPROP 1 LAST MATERIAL CHIP
J 0
(-4975 1900);
DISPLAY 0.510638 (-4975 1900);
FORCEPROP 1 LAST TOLERANCE 5%
J 0
(-5050 1900);
DISPLAY 0.510638 (-5050 1900);
FORCEPROP 1 LAST LOCATION R3637
J 0
(-5500 1900);
DISPLAY 0.638298 (-5500 1900);
FORCEPROP 1 LASTPIN (-5400 1900) $PN 1
J 0
(-5388 1912);
DISPLAY 0.787234 (-5388 1912);
PAINT MONO (-5388 1912);
FORCEPROP 1 LASTPIN (-5200 1900) $PN 2
J 0
(-5238 1912);
DISPLAY 0.787234 (-5238 1912);
PAINT MONO (-5238 1912);
FORCEPROP 2 LAST CDS_LIB pure_quanta
J 0
(-5300 1900);
DISPLAY INVISIBLE (-5300 1900);
FORCEPROP 1 LAST PATH I537
J 0
(-5350 2050);
DISPLAY 0.978723 (-5350 2050);
PAINT WHITE (-5350 2050);
DISPLAY INVISIBLE (-5350 2050);
FORCEPROP 1 LAST PACK_TYPE 0402LF
J 0
(-5375 2000);
DISPLAY 0.319149 (-5375 2000);
DISPLAY INVISIBLE (-5375 2000);
FORCEPROP 1 LAST WATTAGE 1/16W
J 2
(-5175 2000);
DISPLAY 0.319149 (-5175 2000);
DISPLAY INVISIBLE (-5175 2000);
FORCEPROP 0 LAST $SEC 1
J 0
(-5500 1950);
DISPLAY 0.680851 (-5500 1950);
PAINT MONO (-5500 1950);
DISPLAY INVISIBLE (-5500 1950);
FORCEPROP 0 LAST CDS_SEC 1
J 0
(-5500 1950);
DISPLAY 1.021277 (-5500 1950);
DISPLAY INVISIBLE (-5500 1950);
FORCEADD OFFPAGE..1
(-8175 2050);
FORCEPROP 2 LAST $XR0 213 
J 0
(-8427 2050);
DISPLAY 0.638298 (-8427 2050);
PAINT MONO (-8427 2050);
FORCEPROP 1 LAST OFFPAGE TRUE
J 0
(-7850 1925);
DISPLAY 0.872340 (-7850 1925);
PAINT GREEN (-7850 1925);
DISPLAY INVISIBLE (-7850 1925);
FORCEPROP 1 LAST COMMENT_BODY TRUE
J 0
(-8050 1950);
DISPLAY 0.872340 (-8050 1950);
PAINT GREEN (-8050 1950);
DISPLAY INVISIBLE (-8050 1950);
FORCEPROP 2 LAST PATH I538
J 0
(-8125 2125);
DISPLAY 1.021277 (-8125 2125);
DISPLAY INVISIBLE (-8125 2125);
FORCEPROP 2 LAST CDS_LIB standard
J 0
(-8175 2050);
DISPLAY INVISIBLE (-8175 2050);
FORCEADD Q_RES..2
(-7450 2425);
FORCEPROP 1 LAST PART_NUMBER CS31002FB08
J 0
(-7410 2300);
DISPLAY 0.510638 (-7410 2300);
DISPLAY INVISIBLE (-7410 2300);
FORCEPROP 1 LAST TOLERANCE 1%
J 0
(-7405 2450);
DISPLAY 0.510638 (-7405 2450);
FORCEPROP 1 LAST WATTAGE 1/16W
J 0
(-7410 2400);
DISPLAY 0.510638 (-7410 2400);
FORCEPROP 1 LAST PACK_TYPE 0402LF
J 0
(-7410 2250);
DISPLAY 0.510638 (-7410 2250);
FORCEPROP 1 LAST VALUE 10K
J 0
(-7405 2500);
DISPLAY 0.510638 (-7405 2500);
FORCEPROP 1 LAST MATERIAL CHIP
J 0
(-7410 2350);
DISPLAY 0.510638 (-7410 2350);
FORCEPROP 1 LAST $LOCATION R4516
J 0
(-7405 2550);
DISPLAY 0.978723 (-7405 2550);
FORCEPROP 1 LASTPIN (-7450 2525) $PN 1
J 0
(-7445 2487);
DISPLAY 0.787234 (-7445 2487);
PAINT MONO (-7445 2487);
FORCEPROP 1 LASTPIN (-7450 2325) $PN 2
J 0
(-7445 2335);
DISPLAY 0.787234 (-7445 2335);
PAINT MONO (-7445 2335);
FORCEPROP 2 LAST CDS_LIB pure_quanta
J 0
(-7450 2425);
DISPLAY INVISIBLE (-7450 2425);
FORCEPROP 1 LAST PATH I539
J 0
(-7400 2600);
DISPLAY 0.978723 (-7400 2600);
PAINT WHITE (-7400 2600);
DISPLAY INVISIBLE (-7400 2600);
FORCEPROP 0 LAST CDS_LOCATION R4516
J 0
(-7400 2600);
DISPLAY 1.021277 (-7400 2600);
DISPLAY INVISIBLE (-7400 2600);
FORCEPROP 0 LAST $SEC 1
J 0
(-7400 2600);
DISPLAY 0.680851 (-7400 2600);
PAINT MONO (-7400 2600);
DISPLAY INVISIBLE (-7400 2600);
FORCEPROP 0 LAST CDS_SEC 1
J 0
(-7400 2600);
DISPLAY 1.021277 (-7400 2600);
DISPLAY INVISIBLE (-7400 2600);
FORCEADD Q_RES..2
(-7125 2425);
FORCEPROP 1 LAST PART_NUMBER CS31002FB08
J 0
(-7085 2300);
DISPLAY 0.510638 (-7085 2300);
DISPLAY INVISIBLE (-7085 2300);
FORCEPROP 1 LAST PACK_TYPE 0402LF
J 0
(-7085 2250);
DISPLAY 0.510638 (-7085 2250);
FORCEPROP 1 LAST TOLERANCE 1%
J 0
(-7080 2450);
DISPLAY 0.510638 (-7080 2450);
FORCEPROP 1 LAST WATTAGE 1/16W
J 0
(-7085 2400);
DISPLAY 0.510638 (-7085 2400);
FORCEPROP 1 LAST MATERIAL CHIP
J 0
(-7085 2350);
DISPLAY 0.510638 (-7085 2350);
FORCEPROP 1 LAST VALUE 10K
J 0
(-7080 2500);
DISPLAY 0.510638 (-7080 2500);
FORCEPROP 1 LAST $LOCATION R4517
J 0
(-7080 2550);
DISPLAY 0.978723 (-7080 2550);
FORCEPROP 1 LASTPIN (-7125 2525) $PN 1
J 0
(-7120 2487);
DISPLAY 0.787234 (-7120 2487);
PAINT MONO (-7120 2487);
FORCEPROP 1 LASTPIN (-7125 2325) $PN 2
J 0
(-7120 2335);
DISPLAY 0.787234 (-7120 2335);
PAINT MONO (-7120 2335);
FORCEPROP 2 LAST CDS_LIB pure_quanta
J 0
(-7125 2425);
DISPLAY INVISIBLE (-7125 2425);
FORCEPROP 1 LAST PATH I540
J 0
(-7075 2600);
DISPLAY 0.978723 (-7075 2600);
PAINT WHITE (-7075 2600);
DISPLAY INVISIBLE (-7075 2600);
FORCEPROP 0 LAST CDS_LOCATION R4517
J 0
(-7075 2600);
DISPLAY 1.021277 (-7075 2600);
DISPLAY INVISIBLE (-7075 2600);
FORCEPROP 0 LAST $SEC 1
J 0
(-7075 2600);
DISPLAY 0.680851 (-7075 2600);
PAINT MONO (-7075 2600);
DISPLAY INVISIBLE (-7075 2600);
FORCEPROP 0 LAST CDS_SEC 1
J 0
(-7075 2600);
DISPLAY 1.021277 (-7075 2600);
DISPLAY INVISIBLE (-7075 2600);
FORCEADD UNIVERSAL_POWER..1
(-7450 2775);
FORCEPROP 3 LASTPIN (-7450 2725) SIG_NAME P3V3\g
J 0
(-7440 2735);
DISPLAY 0.659574 (-7440 2735);
PAINT MONO (-7440 2735);
DISPLAY INVISIBLE (-7440 2735);
FORCEPROP 1 LAST HDL_POWER P3V3
J 1
(-7450 2825);
DISPLAY 0.872340 (-7450 2825);
PAINT GREEN (-7450 2825);
FORCEPROP 1 LAST PATH I541
J 0
(-7400 2800);
DISPLAY 0.872340 (-7400 2800);
PAINT AQUA (-7400 2800);
DISPLAY INVISIBLE (-7400 2800);
FORCEPROP 2 LAST CDS_LIB logical_power
J 0
(-7450 2775);
DISPLAY INVISIBLE (-7450 2775);
FORCEADD DESIGN_NOTE..1
(-7875 175);
FORCEPROP 1 LAST COMMENT_BODY TRUE
J 0
(-7850 275);
DISPLAY 0.978723 (-7850 275);
DISPLAY INVISIBLE (-7850 275);
FORCEPROP 2 LAST CDS_LIB logical_power
J 0
(-7875 175);
PAINT MONO (-7875 175);
DISPLAY INVISIBLE (-7875 175);
FORCEADD DNS..1
(-9225 600);
PAINT RED (-9225 600);
FORCEPROP 1 LAST COMMENT_BODY TRUE
R 1
J 0
(-9150 375);
DISPLAY 0.872340 (-9150 375);
PAINT GREEN (-9150 375);
DISPLAY INVISIBLE (-9150 375);
FORCEPROP 2 LAST CDS_LIB mstr_misc
J 0
(-9225 600);
PAINT MONO (-9225 600);
DISPLAY INVISIBLE (-9225 600);
FORCEADD DESIGN_NOTE..1
(-2325 5150);
FORCEPROP 0 LAST S7 PORT 9/10: GPU BOARD
J 0
(-2525 4800);
DISPLAY 1.021277 (-2525 4800);
PAINT SKYBLUE (-2525 4800);
FORCEPROP 0 LAST S9 PORT 8: SWB BOARD
J 0
(-2525 4900);
DISPLAY 1.021277 (-2525 4900);
PAINT SKYBLUE (-2525 4900);
FORCEPROP 0 LAST S4 PORT 0-3/4-7: CPU0/CPU1
J 0
(-2525 5000);
DISPLAY 1.021277 (-2525 5000);
PAINT SKYBLUE (-2525 5000);
FORCEPROP 0 LAST S10 PORT 14-17 OCP_V3_2
J 0
(-2525 4700);
DISPLAY 1.021277 (-2525 4700);
PAINT SKYBLUE (-2525 4700);
FORCEPROP 2 LAST CDS_LIB logical_power
J 0
(-2325 5150);
DISPLAY INVISIBLE (-2325 5150);
FORCEPROP 1 LAST COMMENT_BODY TRUE
J 0
(-2300 5250);
DISPLAY 0.978723 (-2300 5250);
DISPLAY INVISIBLE (-2300 5250);
FORCEADD DNS..1
(-8825 2025);
PAINT RED (-8825 2025);
FORCEPROP 1 LAST COMMENT_BODY TRUE
R 1
J 0
(-8750 1800);
DISPLAY 0.872340 (-8750 1800);
PAINT GREEN (-8750 1800);
DISPLAY INVISIBLE (-8750 1800);
FORCEPROP 2 LAST CDS_LIB mstr_misc
J 0
(-8825 2025);
PAINT MONO (-8825 2025);
DISPLAY INVISIBLE (-8825 2025);
FORCEADD DNS..1
(-9225 2025);
PAINT RED (-9225 2025);
FORCEPROP 1 LAST COMMENT_BODY TRUE
R 1
J 0
(-9150 1800);
DISPLAY 0.872340 (-9150 1800);
PAINT GREEN (-9150 1800);
DISPLAY INVISIBLE (-9150 1800);
FORCEPROP 2 LAST CDS_LIB mstr_misc
J 0
(-9225 2025);
PAINT MONO (-9225 2025);
DISPLAY INVISIBLE (-9225 2025);
FORCEADD QUANTA_TITLE_BLOCK_C..1
(-425 -675);
FORCEPROP 0 LAST CDS_CON_LAST_MODIFIED Fri Aug 25 14:03:22 2023
J 0
(-2310 -660);
PAINT MONO (-2310 -660);
DISPLAY INVISIBLE (-2310 -660);
FORCEPROP 2 LAST CUSTOM_TXT_CDS <XR_PAGE_TITLE>
J 0
(-8315 4575);
DISPLAY 0.638298 (-8315 4575);
PAINT PINK (-8315 4575);
DISPLAY INVISIBLE (-8315 4575);
FORCEPROP 2 LAST CUSTOM_TXT_CDS <CON_LAST_MODIFIED>
J 0
(-2375 -650);
DISPLAY 0.978723 (-2375 -650);
FORCEPROP 2 LAST CUSTOM_TXT_CDS <Q_REV>
J 0
(-609 -572);
DISPLAY 1.212766 (-609 -572);
FORCEPROP 2 LAST CUSTOM_TXT_CDS <Q_NUMBER>
J 0
(-1828 -572);
DISPLAY 1.212766 (-1828 -572);
FORCEPROP 2 LAST CUSTOM_TXT_CDS <CON_PAGE_NUM> OF <CON_TOTAL_PAGES>
J 0
(-871 -657);
DISPLAY 0.978723 (-871 -657);
FORCEPROP 2 LAST CUSTOM_TXT_CDS <NAME_2>
J 0
(-3600 -625);
FORCEPROP 2 LAST CUSTOM_TXT_CDS <NAME_1>
J 0
(-3600 -500);
FORCEPROP 2 LAST CUSTOM_TXT_CDS <Q_PROJ>
J 0
(-2807 -573);
DISPLAY 1.212766 (-2807 -573);
FORCEPROP 1 LAST Q_TITLE CLK- DB2000QL CLK BUFFER (1/2)
J 0
(-9766 -649);
DISPLAY 1.957447 (-9766 -649);
PAINT GREEN (-9766 -649);
FORCEPROP 1 LAST Q_DEPT 
J 1
(-4188 -626);
DISPLAY 1.957447 (-4188 -626);
PAINT GREEN (-4188 -626);
FORCEPROP 2 LAST CDS_XR_PAGE_TITLE CR-206 : @S9S_MB_2U_LIB.S9S_MB_2U(SCH_1):PAGE206
J 0
(-8315 4575);
DISPLAY 0.638298 (-8315 4575);
PAINT PINK (-8315 4575);
DISPLAY INVISIBLE (-8315 4575);
FORCEPROP 2 LAST CDS_LIB pure_quanta
J 0
(-425 -675);
PAINT MONO (-425 -675);
DISPLAY INVISIBLE (-425 -675);
FORCEPROP 1 LAST CDS_LMAN_SYM_OUTLINE -9475,6775,100,-125
J 0
(-425 -675);
DISPLAY 0.468085 (-425 -675);
PAINT GREEN (-425 -675);
DISPLAY INVISIBLE (-425 -675);
FORCEPROP 2 LAST PAGE_BORDER TRUE
J 0
(-8315 4575);
DISPLAY 0.638298 (-8315 4575);
PAINT PINK (-8315 4575);
DISPLAY INVISIBLE (-8315 4575);
FORCEPROP 1 LAST COMMENT_BODY TRUE
J 0
(-413 -688);
DISPLAY 0.978723 (-413 -688);
PAINT GREEN (-413 -688);
DISPLAY INVISIBLE (-413 -688);
WIRE 16 -1 (-7450 2725)(-7450 2675);
WIRE 16 -1 (-9425 4200)(-9425 4450);
WIRE 16 -1 (-9200 4200)(-9425 4200);
WIRE 16 -1 (-7075 3325)(-7075 3400);
WIRE 16 -1 (-7075 3325)(-7450 3325);
WIRE 16 -1 (-7075 3200)(-7075 3325);
WIRE 16 -1 (-9225 2275)(-9225 2325);
WIRE 16 -1 (-8825 2275)(-9225 2275);
WIRE 16 -1 (-9225 2150)(-9225 2275);
WIRE 16 -1 (-4125 4100)(-4125 4200);
WIRE 16 -1 (-4125 4050)(-4125 4100);
WIRE 16 -1 (-4125 4100)(-3775 4100);
WIRE 16 -1 (-7075 4200)(-7075 4275);
WIRE 16 -1 (-7075 4200)(-7450 4200);
WIRE 16 -1 (-7075 4075)(-7075 4200);
WIRE 16 -1 (-7300 5225)(-7300 5450);
WIRE 16 -1 (-7300 5225)(-7725 5225);
WIRE 16 -1 (-7300 5075)(-7300 5225);
WIRE 16 -1 (-5025 4400)(-5025 3800);
WIRE 16 -1 (-9225 725)(-9225 850);
WIRE 16 -1 (-9425 5225)(-9425 5475);
WIRE 16 -1 (-9200 5225)(-9425 5225);
WIRE 16 -1 (-4575 4300)(-4575 3850);
WIRE 16 -1 (-2175 425)(-2175 500);
WIRE 16 -1 (-9225 1275)(-9225 1375);
WIRE 16 -1 (-9225 -150)(-9225 -50);
WIRE 16 -1 (-7300 4750)(-7300 4775);
WIRE 16 -1 (-6575 2375)(-6575 2400);
WIRE 16 -1 (-7075 2825)(-7075 2875);
WIRE 16 -1 (-7075 3700)(-7075 3750);
WIRE 16 -1 (-8825 1275)(-8825 1375);
WIRE 16 -1 (-8825 1575)(-8825 1750);
WIRE 16 -1 (-8825 1750)(-8150 1750);
FORCEPROP 2 LAST SIG_NAME PD_DB2000_SMB_SA0
J 0
(-8735 1760);
DISPLAY 0.680851 (-8735 1760);
PAINT WHITE (-8735 1760);
WIRE 16 -1 (-8825 1950)(-8825 1750);
WIRE 16 -1 (-5625 1900)(-5400 1900);
WIRE 16 -1 (-5625 1950)(-5625 1900);
WIRE 16 -1 (-5400 1950)(-5625 1950);
WIRE 16 -1 (-5625 1950)(-5625 2000);
WIRE 16 -1 (-5400 2000)(-5625 2000);
WIRE 16 -1 (-5625 2000)(-5625 2050);
WIRE 16 -1 (-5400 2050)(-5625 2050);
WIRE 16 -1 (-7125 2325)(-7125 2050);
WIRE 16 -1 (-7125 2050)(-5625 2050);
WIRE 16 -1 (-8125 2050)(-7125 2050);
FORCEPROP 2 LAST SIG_NAME OCP_SFF_CLK_OE_N
J 0
(-8035 2060);
DISPLAY 0.680851 (-8035 2060);
PAINT WHITE (-8035 2060);
WIRE 16 -1 (-7125 2675)(-7125 2525);
WIRE 16 -1 (-7450 2675)(-7125 2675);
WIRE 16 -1 (-7450 2525)(-7450 2675);
WIRE 16 -1 (-7450 2100)(-8125 2100);
FORCEPROP 2 LAST SIG_NAME CLK_SWB_OE_N
J 0
(-8035 2110);
DISPLAY 0.680851 (-8035 2110);
PAINT WHITE (-8035 2110);
WIRE 16 -1 (-7450 2325)(-7450 2100);
WIRE 16 -1 (-5400 2100)(-7450 2100);
WIRE 16 -1 (-9000 4200)(-8200 4200);
FORCEPROP 2 LAST SIG_NAME P3V3_DB2000_FB_VDD
J 0
(-8910 4210);
DISPLAY 0.808511 (-8910 4210);
PAINT WHITE (-8910 4210);
WIRE 16 -1 (-7975 4200)(-8200 4200);
WIRE 16 -1 (-8200 4200)(-8200 3325);
WIRE 16 -1 (-7975 3325)(-8200 3325);
WIRE 16 -1 (-7450 3325)(-7775 3325);
WIRE 16 -1 (-7450 3200)(-7450 3325);
WIRE 16 -1 (-6150 2250)(-5400 2250);
FORCEPROP 2 LAST SIG_NAME FM_DB2000_OE_N
J 0
(-6060 2260);
DISPLAY 0.680851 (-6060 2260);
PAINT WHITE (-6060 2260);
WIRE 16 -1 (-6150 2575)(-5725 2575);
FORCEPROP 2 LAST SIG_NAME FM_PLD_CLKS_DEV_EN
J 0
(-6060 2585);
DISPLAY 0.680851 (-6060 2585);
PAINT WHITE (-6060 2585);
WIRE 16 -1 (-5725 2400)(-6125 2400);
WIRE 16 -1 (-5725 2550)(-5725 2400);
WIRE 16 -1 (-5725 2575)(-5725 2550);
WIRE 16 -1 (-5725 2550)(-5400 2550);
WIRE 16 -1 (-6575 2400)(-6325 2400);
WIRE 16 -1 (-8825 2150)(-8825 2275);
WIRE 16 3135 (-6900 75)(-7825 75);
WIRE 16 3135 (-6900 -125)(-6900 75);
WIRE 16 3135 (-7825 75)(-8075 75);
WIRE 16 3135 (-8075 75)(-8075 -125);
WIRE 16 3135 (-6900 -325)(-6900 -125);
WIRE 16 3135 (-6900 -125)(-7825 -125);
WIRE 16 3135 (-7825 75)(-7825 -125);
WIRE 16 3135 (-7825 -125)(-8075 -125);
WIRE 16 3135 (-7825 -125)(-7825 -325);
WIRE 16 3135 (-7825 -325)(-6900 -325);
WIRE 16 3135 (-8075 -125)(-8075 -325);
WIRE 16 3135 (-8075 -325)(-7825 -325);
WIRE 16 -1 (-3775 1000)(-4825 1000);
FORCEPROP 2 LAST SIG_NAME NC_CLK_100M_DB2000_NC13
J 0
(-4685 1010);
DISPLAY 0.680851 (-4685 1010);
PAINT WHITE (-4685 1010);
WIRE 16 -1 (-9225 150)(-9225 325);
WIRE 16 -1 (-9225 325)(-8600 325);
FORCEPROP 2 LAST SIG_NAME FM_DB2000_VSBEN
J 0
(-9135 335);
DISPLAY 0.680851 (-9135 335);
PAINT WHITE (-9135 335);
WIRE 16 -1 (-9225 525)(-9225 325);
WIRE 16 -1 (-3775 850)(-4825 850);
FORCEPROP 2 LAST SIG_NAME NC_CLK_100M_DB2000_NC16
J 0
(-4685 860);
DISPLAY 0.680851 (-4685 860);
PAINT WHITE (-4685 860);
WIRE 16 -1 (-3775 950)(-4825 950);
FORCEPROP 2 LAST SIG_NAME NC_CLK_100M_DB2000_NC14
J 0
(-4685 960);
DISPLAY 0.680851 (-4685 960);
PAINT WHITE (-4685 960);
WIRE 16 -1 (-3775 800)(-4825 800);
FORCEPROP 2 LAST SIG_NAME NC_CLK_100M_DB2000_NC17
J 0
(-4685 810);
DISPLAY 0.680851 (-4685 810);
PAINT WHITE (-4685 810);
WIRE 16 -1 (-3775 1400)(-4825 1400);
FORCEPROP 2 LAST SIG_NAME NC_CLK_100M_DB2000_NC5
J 0
(-4685 1410);
DISPLAY 0.680851 (-4685 1410);
PAINT WHITE (-4685 1410);
WIRE 16 -1 (-3775 1350)(-4825 1350);
FORCEPROP 2 LAST SIG_NAME NC_CLK_100M_DB2000_NC6
J 0
(-4685 1360);
DISPLAY 0.680851 (-4685 1360);
PAINT WHITE (-4685 1360);
WIRE 16 -1 (-1300 3850)(-2625 3850);
FORCEPROP 2 LAST SIG_NAME CLK_100M_DB2000_CPU0_BCLK1_DP
J 0
(-2460 3860);
DISPLAY 0.680851 (-2460 3860);
PAINT WHITE (-2460 3860);
WIRE 16 -1 (-1300 4000)(-2625 4000);
FORCEPROP 2 LAST SIG_NAME CLK_100M_DB2000_CPU0_BCLK0_DP
J 0
(-2460 4010);
DISPLAY 0.680851 (-2460 4010);
PAINT WHITE (-2460 4010);
WIRE 16 -1 (-1300 3800)(-2625 3800);
FORCEPROP 2 LAST SIG_NAME CLK_100M_DB2000_CPU0_BCLK1_DN
J 0
(-2460 3810);
DISPLAY 0.680851 (-2460 3810);
PAINT WHITE (-2460 3810);
WIRE 16 -1 (-3775 3450)(-4825 3450);
FORCEPROP 2 LAST SIG_NAME PD_DB2000_SMB_SA1
J 0
(-4685 3460);
DISPLAY 0.553191 (-4685 3460);
PAINT WHITE (-4685 3460);
WIRE 16 -1 (-1300 3950)(-2625 3950);
FORCEPROP 2 LAST SIG_NAME CLK_100M_DB2000_CPU0_BCLK0_DN
J 0
(-2460 3960);
DISPLAY 0.680851 (-2460 3960);
PAINT WHITE (-2460 3960);
WIRE 16 -1 (-1300 3700)(-2625 3700);
FORCEPROP 2 LAST SIG_NAME CLK_100M_DB2000_CPU0_BCLK2_DP
J 0
(-2460 3710);
DISPLAY 0.680851 (-2460 3710);
PAINT WHITE (-2460 3710);
WIRE 16 -1 (-1300 3550)(-2625 3550);
FORCEPROP 2 LAST SIG_NAME CLK_100M_DB2000_CPU0_BCLK3_DP
J 0
(-2460 3560);
DISPLAY 0.680851 (-2460 3560);
PAINT WHITE (-2460 3560);
WIRE 16 -1 (-1300 1600)(-2625 1600);
FORCEPROP 2 LAST SIG_NAME CLK_100M_OCP_V3_2_C_R_DP
J 0
(-2460 1610);
DISPLAY 0.702128 (-2460 1610);
PAINT WHITE (-2460 1610);
WIRE 16 -1 (-3775 3300)(-4825 3300);
FORCEPROP 2 LAST SIG_NAME SMB_HOST_DB2000_3V3AUX_SDA
J 0
(-4685 3310);
DISPLAY 0.553191 (-4685 3310);
PAINT WHITE (-4685 3310);
WIRE 16 -1 (-3775 3400)(-4825 3400);
FORCEPROP 2 LAST SIG_NAME PD_DB2000_SMB_SA0
J 0
(-4685 3410);
DISPLAY 0.553191 (-4685 3410);
PAINT WHITE (-4685 3410);
WIRE 16 -1 (-3775 1200)(-4825 1200);
FORCEPROP 2 LAST SIG_NAME NC_CLK_100M_DB2000_NC9
J 0
(-4685 1210);
DISPLAY 0.680851 (-4685 1210);
PAINT WHITE (-4685 1210);
WIRE 16 -1 (-3775 1300)(-4825 1300);
FORCEPROP 2 LAST SIG_NAME NC_CLK_100M_DB2000_NC7
J 0
(-4685 1310);
DISPLAY 0.680851 (-4685 1310);
PAINT WHITE (-4685 1310);
WIRE 16 -1 (-3775 1150)(-4825 1150);
FORCEPROP 2 LAST SIG_NAME NC_CLK_100M_DB2000_NC10
J 0
(-4685 1160);
DISPLAY 0.680851 (-4685 1160);
PAINT WHITE (-4685 1160);
WIRE 16 -1 (-3775 1050)(-4825 1050);
FORCEPROP 2 LAST SIG_NAME NC_CLK_100M_DB2000_NC12
J 0
(-4685 1060);
DISPLAY 0.680851 (-4685 1060);
PAINT WHITE (-4685 1060);
WIRE 16 -1 (-3775 900)(-4825 900);
FORCEPROP 2 LAST SIG_NAME NC_CLK_100M_DB2000_NC15
J 0
(-4685 910);
DISPLAY 0.680851 (-4685 910);
PAINT WHITE (-4685 910);
WIRE 16 -1 (-1300 3650)(-2625 3650);
FORCEPROP 2 LAST SIG_NAME CLK_100M_DB2000_CPU0_BCLK2_DN
J 0
(-2460 3660);
DISPLAY 0.680851 (-2460 3660);
PAINT WHITE (-2460 3660);
WIRE 16 -1 (-1300 3500)(-2625 3500);
FORCEPROP 2 LAST SIG_NAME CLK_100M_DB2000_CPU0_BCLK3_DN
J 0
(-2460 3510);
DISPLAY 0.680851 (-2460 3510);
PAINT WHITE (-2460 3510);
WIRE 16 -1 (-3775 3650)(-4825 3650);
FORCEPROP 2 LAST SIG_NAME CLK_100M_DB2000_DP
J 0
(-4685 3660);
DISPLAY 0.553191 (-4685 3660);
PAINT WHITE (-4685 3660);
WIRE 16 -1 (-3775 3600)(-4825 3600);
FORCEPROP 2 LAST SIG_NAME CLK_100M_DB2000_DN
J 0
(-4685 3610);
DISPLAY 0.553191 (-4685 3610);
PAINT WHITE (-4685 3610);
WIRE 16 -1 (-1300 3400)(-2625 3400);
FORCEPROP 2 LAST SIG_NAME CLK_100M_DB2000_CPU1_BCLK0_DP
J 0
(-2460 3410);
DISPLAY 0.680851 (-2460 3410);
PAINT WHITE (-2460 3410);
WIRE 16 -1 (-1300 3250)(-2625 3250);
FORCEPROP 2 LAST SIG_NAME CLK_100M_DB2000_CPU1_BCLK1_DP
J 0
(-2460 3260);
DISPLAY 0.680851 (-2460 3260);
PAINT WHITE (-2460 3260);
WIRE 16 -1 (-1300 3100)(-2625 3100);
FORCEPROP 2 LAST SIG_NAME CLK_100M_DB2000_CPU1_BCLK2_DP
J 0
(-2460 3110);
DISPLAY 0.680851 (-2460 3110);
PAINT WHITE (-2460 3110);
WIRE 16 -1 (-3775 750)(-4825 750);
FORCEPROP 2 LAST SIG_NAME NC_CLK_100M_DB2000_NC18
J 0
(-4685 760);
DISPLAY 0.680851 (-4685 760);
PAINT WHITE (-4685 760);
WIRE 16 -1 (-3775 3250)(-4825 3250);
FORCEPROP 2 LAST SIG_NAME SMB_HOST_DB2000_3V3AUX_SCL
J 0
(-4685 3260);
DISPLAY 0.553191 (-4685 3260);
PAINT WHITE (-4685 3260);
WIRE 16 -1 (-1300 2950)(-2625 2950);
FORCEPROP 2 LAST SIG_NAME CLK_100M_DB2000_CPU1_BCLK3_DP
J 0
(-2460 2960);
DISPLAY 0.680851 (-2460 2960);
PAINT WHITE (-2460 2960);
WIRE 16 -1 (-3775 2550)(-5200 2550);
FORCEPROP 2 LAST SIG_NAME FM_DB2000_DEV_EN
J 0
(-4685 2560);
DISPLAY 0.680851 (-4685 2560);
PAINT WHITE (-4685 2560);
WIRE 16 -1 (-2625 1700)(-1300 1700);
FORCEPROP 2 LAST SIG_NAME CLK_100M_OCP_V3_2_B_R_DN
J 0
(-2460 1710);
DISPLAY 0.702128 (-2460 1710);
PAINT WHITE (-2460 1710);
WIRE 16 -1 (-2625 1750)(-1300 1750);
FORCEPROP 2 LAST SIG_NAME CLK_100M_OCP_V3_2_B_R_DP
J 0
(-2460 1760);
DISPLAY 0.702128 (-2460 1760);
PAINT WHITE (-2460 1760);
WIRE 16 -1 (-1300 3200)(-2625 3200);
FORCEPROP 2 LAST SIG_NAME CLK_100M_DB2000_CPU1_BCLK1_DN
J 0
(-2460 3210);
DISPLAY 0.680851 (-2460 3210);
PAINT WHITE (-2460 3210);
WIRE 16 -1 (-1300 3050)(-2625 3050);
FORCEPROP 2 LAST SIG_NAME CLK_100M_DB2000_CPU1_BCLK2_DN
J 0
(-2460 3060);
DISPLAY 0.680851 (-2460 3060);
PAINT WHITE (-2460 3060);
WIRE 16 -1 (-1300 2800)(-2625 2800);
FORCEPROP 2 LAST SIG_NAME CLK_100M_GPU_SWB_REF_DP
J 0
(-2460 2810);
DISPLAY 0.680851 (-2460 2810);
PAINT WHITE (-2460 2810);
WIRE 16 -1 (-3775 1100)(-4825 1100);
FORCEPROP 2 LAST SIG_NAME NC_CLK_100M_DB2000_NC11
J 0
(-4685 1110);
DISPLAY 0.680851 (-4685 1110);
PAINT WHITE (-4685 1110);
WIRE 16 -1 (-3775 1250)(-4825 1250);
FORCEPROP 2 LAST SIG_NAME NC_CLK_100M_DB2000_NC8
J 0
(-4685 1260);
DISPLAY 0.680851 (-4685 1260);
PAINT WHITE (-4685 1260);
WIRE 16 -1 (-3775 1500)(-4825 1500);
FORCEPROP 2 LAST SIG_NAME NC_CLK_100M_DB2000_NC3
J 0
(-4685 1510);
DISPLAY 0.680851 (-4685 1510);
PAINT WHITE (-4685 1510);
WIRE 16 -1 (-3775 1450)(-4825 1450);
FORCEPROP 2 LAST SIG_NAME NC_CLK_100M_DB2000_NC4
J 0
(-4685 1460);
DISPLAY 0.680851 (-4685 1460);
PAINT WHITE (-4685 1460);
WIRE 16 -1 (-1300 1850)(-2625 1850);
FORCEPROP 2 LAST SIG_NAME CLK_100M_OCP_V3_2_A_R_DN
J 0
(-2460 1860);
DISPLAY 0.702128 (-2460 1860);
PAINT WHITE (-2460 1860);
WIRE 16 -1 (-3775 2000)(-5200 2000);
FORCEPROP 2 LAST SIG_NAME FM_DB2000_10_OE_N
J 0
(-4685 2010);
DISPLAY 0.680851 (-4685 2010);
PAINT WHITE (-4685 2010);
WIRE 16 -1 (-5200 1900)(-3775 1900);
FORCEPROP 2 LAST SIG_NAME FM_DB2000_12_OE_N
J 0
(-4685 1910);
DISPLAY 0.680851 (-4685 1910);
PAINT WHITE (-4685 1910);
WIRE 16 -1 (-3775 2100)(-5200 2100);
FORCEPROP 2 LAST SIG_NAME FM_DB2000_8_OE_N
J 0
(-4685 2110);
DISPLAY 0.680851 (-4685 2110);
PAINT WHITE (-4685 2110);
WIRE 16 -1 (-9225 1575)(-9225 1800);
WIRE 16 -1 (-8150 1800)(-9225 1800);
FORCEPROP 2 LAST SIG_NAME PD_DB2000_SMB_SA1
J 0
(-8735 1810);
DISPLAY 0.680851 (-8735 1810);
PAINT WHITE (-8735 1810);
WIRE 16 -1 (-9225 1950)(-9225 1800);
WIRE 16 -1 (-2175 500)(-2625 500);
WIRE 16 -1 (-8875 4775)(-8875 4900);
WIRE 16 -1 (-7300 4775)(-7300 4875);
WIRE 16 -1 (-8475 4775)(-8875 4775);
WIRE 16 -1 (-8475 4900)(-8475 4775);
WIRE 16 -1 (-8100 4775)(-8475 4775);
WIRE 16 -1 (-8100 4900)(-8100 4775);
WIRE 16 -1 (-7725 4900)(-7725 4775);
WIRE 16 -1 (-7300 4775)(-7725 4775);
WIRE 16 -1 (-7725 4775)(-8100 4775);
WIRE 16 -1 (-7450 3875)(-7450 3750);
WIRE 16 -1 (-7075 3750)(-7450 3750);
WIRE 16 -1 (-7075 3875)(-7075 3750);
WIRE 16 -1 (-8875 5100)(-8875 5225);
WIRE 16 -1 (-9000 5225)(-8875 5225);
WIRE 16 -1 (-8475 5100)(-8475 5225);
WIRE 16 -1 (-8475 5225)(-8875 5225);
WIRE 16 -1 (-8100 5225)(-8475 5225);
WIRE 16 -1 (-8100 5100)(-8100 5225);
WIRE 16 -1 (-7725 5225)(-8100 5225);
WIRE 16 -1 (-7725 5100)(-7725 5225);
WIRE 16 -1 (-7450 4075)(-7450 4200);
WIRE 16 -1 (-7450 4200)(-7775 4200);
WIRE 16 -1 (-5025 3800)(-3775 3800);
WIRE 16 -1 (-4575 3850)(-3775 3850);
WIRE 16 -1 (-4125 3950)(-3775 3950);
WIRE 16 -1 (-4125 4000)(-4125 3950);
WIRE 16 -1 (-4125 4000)(-3775 4000);
WIRE 16 -1 (-4125 4050)(-4125 4000);
WIRE 16 -1 (-4125 4050)(-3775 4050);
WIRE 16 -1 (-3775 3050)(-4825 3050);
FORCEPROP 2 LAST SIG_NAME FM_DB2000_VSBEN
J 0
(-4685 3060);
DISPLAY 0.553191 (-4685 3060);
PAINT WHITE (-4685 3060);
WIRE 16 -1 (-1300 3350)(-2625 3350);
FORCEPROP 2 LAST SIG_NAME CLK_100M_DB2000_CPU1_BCLK0_DN
J 0
(-2460 3360);
DISPLAY 0.680851 (-2460 3360);
PAINT WHITE (-2460 3360);
WIRE 16 -1 (-5200 1950)(-3775 1950);
FORCEPROP 2 LAST SIG_NAME FM_DB2000_11_OE_N
J 0
(-4685 1960);
DISPLAY 0.680851 (-4685 1960);
PAINT WHITE (-4685 1960);
WIRE 16 -1 (-7075 3000)(-7075 2875);
WIRE 16 -1 (-7075 2875)(-7450 2875);
WIRE 16 -1 (-7450 3000)(-7450 2875);
WIRE 16 -1 (-1300 2000)(-2625 2000);
FORCEPROP 2 LAST SIG_NAME TP_CLK_100M_DIF13_DN
J 0
(-2460 2010);
DISPLAY 0.702128 (-2460 2010);
PAINT WHITE (-2460 2010);
WIRE 16 -1 (-1300 1900)(-2625 1900);
FORCEPROP 2 LAST SIG_NAME CLK_100M_OCP_V3_2_A_R_DP
J 0
(-2460 1910);
DISPLAY 0.702128 (-2460 1910);
PAINT WHITE (-2460 1910);
WIRE 16 -1 (-1300 2750)(-2625 2750);
FORCEPROP 2 LAST SIG_NAME CLK_100M_GPU_SWB_REF_DN
J 0
(-2460 2760);
DISPLAY 0.680851 (-2460 2760);
PAINT WHITE (-2460 2760);
WIRE 16 -1 (-1300 2900)(-2625 2900);
FORCEPROP 2 LAST SIG_NAME CLK_100M_DB2000_CPU1_BCLK3_DN
J 0
(-2460 2910);
DISPLAY 0.680851 (-2460 2910);
PAINT WHITE (-2460 2910);
WIRE 16 -1 (-4725 2150)(-3775 2150);
WIRE 16 -1 (-4725 2150)(-4725 2200);
WIRE 16 -1 (-4725 2200)(-3775 2200);
WIRE 16 -1 (-4725 2200)(-4725 2250);
WIRE 16 -1 (-4725 2250)(-3775 2250);
FORCEPROP 2 LAST SIG_NAME FM_DB2000_1_OE_N
J 0
(-4685 2260);
DISPLAY 0.680851 (-4685 2260);
PAINT WHITE (-4685 2260);
WIRE 16 -1 (-5200 2250)(-4725 2250);
WIRE 16 -1 (-3775 1600)(-4825 1600);
FORCEPROP 2 LAST SIG_NAME NC_CLK_100M_DB2000_NC1
J 0
(-4685 1610);
DISPLAY 0.680851 (-4685 1610);
PAINT WHITE (-4685 1610);
WIRE 16 -1 (-3775 1550)(-4825 1550);
FORCEPROP 2 LAST SIG_NAME NC_CLK_100M_DB2000_NC2
J 0
(-4685 1560);
DISPLAY 0.680851 (-4685 1560);
PAINT WHITE (-4685 1560);
WIRE 16 -1 (-1275 1150)(-2625 1150);
FORCEPROP 2 LAST SIG_NAME TP_CLK_100M_DIF19_DP
J 0
(-2460 1160);
DISPLAY 0.702128 (-2460 1160);
PAINT WHITE (-2460 1160);
WIRE 16 -1 (-1275 1100)(-2625 1100);
FORCEPROP 2 LAST SIG_NAME TP_CLK_100M_DIF19_DN
J 0
(-2460 1110);
DISPLAY 0.702128 (-2460 1110);
PAINT WHITE (-2460 1110);
WIRE 16 -1 (-1300 1250)(-2625 1250);
FORCEPROP 2 LAST SIG_NAME TP_CLK_100M_DIF18_DN
J 0
(-2460 1260);
DISPLAY 0.702128 (-2460 1260);
PAINT WHITE (-2460 1260);
WIRE 16 -1 (-1300 1300)(-2625 1300);
FORCEPROP 2 LAST SIG_NAME TP_CLK_100M_DIF18_DP
J 0
(-2460 1310);
DISPLAY 0.702128 (-2460 1310);
PAINT WHITE (-2460 1310);
WIRE 16 -1 (-1300 1550)(-2625 1550);
FORCEPROP 2 LAST SIG_NAME CLK_100M_OCP_V3_2_C_R_DN
J 0
(-2460 1560);
DISPLAY 0.702128 (-2460 1560);
PAINT WHITE (-2460 1560);
WIRE 16 -1 (-1300 1450)(-2625 1450);
FORCEPROP 2 LAST SIG_NAME CLK_100M_OCP_V3_2_D_R_DP
J 0
(-2460 1460);
DISPLAY 0.702128 (-2460 1460);
PAINT WHITE (-2460 1460);
WIRE 16 -1 (-1300 1400)(-2625 1400);
FORCEPROP 2 LAST SIG_NAME CLK_100M_OCP_V3_2_D_R_DN
J 0
(-2460 1410);
DISPLAY 0.702128 (-2460 1410);
PAINT WHITE (-2460 1410);
WIRE 16 -1 (-3775 2050)(-5200 2050);
FORCEPROP 2 LAST SIG_NAME FM_DB2000_9_OE_N
J 0
(-4685 2060);
DISPLAY 0.680851 (-4685 2060);
PAINT WHITE (-4685 2060);
WIRE 16 -1 (-1300 2050)(-2625 2050);
FORCEPROP 2 LAST SIG_NAME TP_CLK_100M_DIF13_DP
J 0
(-2460 2060);
DISPLAY 0.702128 (-2460 2060);
PAINT WHITE (-2460 2060);
WIRE 16 -1 (-1300 2150)(-2625 2150);
FORCEPROP 2 LAST SIG_NAME CLK_100M_OCP_SFF_3_R_DN
J 0
(-2460 2160);
DISPLAY 0.553191 (-2460 2160);
PAINT WHITE (-2460 2160);
WIRE 16 -1 (-1300 2200)(-2625 2200);
FORCEPROP 2 LAST SIG_NAME CLK_100M_OCP_SFF_3_R_DP
J 0
(-2460 2210);
DISPLAY 0.553191 (-2460 2210);
PAINT WHITE (-2460 2210);
WIRE 16 -1 (-1300 2300)(-2625 2300);
FORCEPROP 2 LAST SIG_NAME CLK_100M_OCP_SFF_2_R_DN
J 0
(-2460 2310);
DISPLAY 0.553191 (-2460 2310);
PAINT WHITE (-2460 2310);
WIRE 16 -1 (-1300 2350)(-2625 2350);
FORCEPROP 2 LAST SIG_NAME CLK_100M_OCP_SFF_2_R_DP
J 0
(-2460 2360);
DISPLAY 0.553191 (-2460 2360);
PAINT WHITE (-2460 2360);
WIRE 16 -1 (-1300 2450)(-2625 2450);
FORCEPROP 2 LAST SIG_NAME CLK_100M_OCP_SFF_1_R_DN
J 0
(-2460 2460);
DISPLAY 0.553191 (-2460 2460);
PAINT WHITE (-2460 2460);
WIRE 16 -1 (-1300 2500)(-2625 2500);
FORCEPROP 2 LAST SIG_NAME CLK_100M_OCP_SFF_1_R_DP
J 0
(-2460 2510);
DISPLAY 0.553191 (-2460 2510);
PAINT WHITE (-2460 2510);
WIRE 16 -1 (-1300 2600)(-2625 2600);
FORCEPROP 2 LAST SIG_NAME CLK_100M_OCP_SFF_0_R_DN
J 0
(-2460 2610);
DISPLAY 0.553191 (-2460 2610);
PAINT WHITE (-2460 2610);
WIRE 16 -1 (-1300 2650)(-2625 2650);
FORCEPROP 2 LAST SIG_NAME CLK_100M_OCP_SFF_0_R_DP
J 0
(-2460 2660);
DISPLAY 0.553191 (-2460 2660);
PAINT WHITE (-2460 2660);
DOT 1 (-5625 1950);
DOT 1 (-5625 2000);
DOT 1 (-4725 2200);
DOT 1 (-4125 4050);
DOT 1 (-4125 4100);
DOT 1 (-7075 3325);
DOT 1 (-7075 2875);
DOT 1 (-7825 -325);
DOT 1 (-7725 5225);
DOT 1 (-7450 3325);
DOT 1 (-9225 325);
DOT 1 (-6900 -125);
DOT 1 (-8075 -125);
DOT 1 (-7825 -125);
DOT 1 (-7825 75);
DOT 1 (-7075 4200);
DOT 1 (-8875 5225);
DOT 1 (-8475 4775);
DOT 1 (-8475 5225);
DOT 1 (-8100 5225);
DOT 1 (-7075 3750);
DOT 1 (-8200 4200);
DOT 1 (-8825 1750);
DOT 1 (-9225 2275);
DOT 1 (-9225 1800);
DOT 1 (-7725 4775);
DOT 1 (-7300 5225);
DOT 1 (-7450 4200);
DOT 1 (-4125 4000);
DOT 1 (-7300 4775);
DOT 1 (-8100 4775);
DOT 1 (-4725 2250);
DOT 1 (-5725 2550);
DOT 1 (-5625 2050);
DOT 1 (-7125 2050);
DOT 1 (-7450 2675);
DOT 1 (-7450 2100);
FORCENOTE
20210603 MODIFY FOR GT
(-4375 -75) 0;
DISPLAY LEFT (-4375 -75);
DISPLAY 2.510638 (-4375 -75);
PAINT PINK (-4375 -75);
FORCENOTE
OE PINS AND SMBUS
(-7775 0) 0;
DISPLAY LEFT (-7775 0);
DISPLAY 0.808511 (-7775 0);
PAINT YELLOW (-7775 0);
FORCENOTE
ENABLE BITS CONTROL OUTPUTS
(-7775 -75) 0;
DISPLAY LEFT (-7775 -75);
DISPLAY 0.638298 (-7775 -75);
PAINT YELLOW (-7775 -75);
FORCENOTE
SIDEBAND INTERFACE
(-7775 -200) 0;
DISPLAY LEFT (-7775 -200);
DISPLAY 0.808511 (-7775 -200);
PAINT YELLOW (-7775 -200);
FORCENOTE
HIGH
(-8025 -250) 0;
DISPLAY LEFT (-8025 -250);
DISPLAY 0.808511 (-8025 -250);
PAINT YELLOW (-8025 -250);
FORCENOTE
CONTROLS OUTPUT ENABLES
(-7775 -275) 0;
DISPLAY LEFT (-7775 -275);
DISPLAY 0.638298 (-7775 -275);
PAINT YELLOW (-7775 -275);
FORCENOTE
LOW
(-8025 -50) 0;
DISPLAY LEFT (-8025 -50);
DISPLAY 0.808511 (-8025 -50);
PAINT YELLOW (-8025 -50);
FORCENOTE
20210603 MODIFY FOR GT
(-4550 5350) 0;
DISPLAY LEFT (-4550 5350);
DISPLAY 2.510638 (-4550 5350);
PAINT PINK (-4550 5350);
FORCENOTE
DB2000 ADDRESS: 0XD8
(-9475 2600) 0;
DISPLAY LEFT (-9475 2600);
DISPLAY 1.595745 (-9475 2600);
PAINT SKYBLUE (-9475 2600);
QUIT
